G04 CAM350 V9.0 (Build 156) Date:  Wed Oct 17 10:51:18 2012 *
G04 Database: (Untitled) *
G04 Layer 26: TSMD.art *
%FSLAX35Y35*%
%MOIN*%
%SFA1.000B1.000*%

%MIA0B0*%
%IPPOS*%
%AMMACRO50_1*
4,1,40,0.01700,-0.01300,0.01700,0.01300,0.01694,0.01370,0.01676,0.01437,0.01646,0.01500,0.01606,0.01557,0.01557,0.01606,0.01500,0.01646,0.01437,0.01676,0.01370,0.01694,0.01300,0.01700,-0.01300,0.01700,-0.01369,0.01694,-0.01437,0.01676,-0.01500,0.01646,-0.01557,0.01606,-0.01606,0.01557,-0.01646,0.01500,-0.01676,0.01437,-0.01694,0.01370,-0.01700,0.01300,-0.01700,-0.01300,-0.01694,-0.01369,-0.01676,-0.01437,-0.01646,-0.01500,-0.01606,-0.01557,-0.01557,-0.01606,-0.01500,-0.01646,-0.01437,-0.01676,-0.01369,-0.01694,-0.01300,-0.01700,0.01300,-0.01700,0.01370,-0.01694,0.01437,-0.01676,0.01500,-0.01646,0.01557,-0.01606,0.01606,-0.01557,0.01646,-0.01500,0.01676,-0.01437,0.01694,-0.01369,0.01700,-0.01300,0.00000*
%
%AMMACRO44_1*
4,1,40,0.01300,0.01700,-0.01300,0.01700,-0.01369,0.01694,-0.01437,0.01676,-0.01500,0.01646,-0.01557,0.01606,-0.01606,0.01557,-0.01646,0.01500,-0.01676,0.01437,-0.01694,0.01370,-0.01700,0.01300,-0.01700,-0.01300,-0.01694,-0.01369,-0.01676,-0.01437,-0.01646,-0.01500,-0.01606,-0.01557,-0.01557,-0.01606,-0.01500,-0.01646,-0.01437,-0.01676,-0.01369,-0.01694,-0.01300,-0.01700,0.01300,-0.01700,0.01370,-0.01694,0.01437,-0.01676,0.01500,-0.01646,0.01557,-0.01606,0.01606,-0.01557,0.01646,-0.01500,0.01676,-0.01437,0.01694,-0.01369,0.01700,-0.01300,0.01700,0.01300,0.01694,0.01370,0.01676,0.01437,0.01646,0.01500,0.01606,0.01557,0.01557,0.01606,0.01500,0.01646,0.01437,0.01676,0.01370,0.01694,0.01300,0.01700,0.00000*
%
%AMMACRO24_1*
4,1,40,0.01100,-0.00700,0.01100,0.00700,0.01094,0.00770,0.01076,0.00837,0.01046,0.00900,0.01006,0.00957,0.00957,0.01006,0.00900,0.01046,0.00837,0.01076,0.00770,0.01094,0.00700,0.01100,-0.00700,0.01100,-0.00769,0.01094,-0.00837,0.01076,-0.00900,0.01046,-0.00957,0.01006,-0.01006,0.00957,-0.01046,0.00900,-0.01076,0.00837,-0.01094,0.00770,-0.01100,0.00700,-0.01100,-0.00700,-0.01094,-0.00769,-0.01076,-0.00837,-0.01046,-0.00900,-0.01006,-0.00957,-0.00957,-0.01006,-0.00900,-0.01046,-0.00837,-0.01076,-0.00769,-0.01094,-0.00700,-0.01100,0.00700,-0.01100,0.00770,-0.01094,0.00837,-0.01076,0.00900,-0.01046,0.00957,-0.01006,0.01006,-0.00957,0.01046,-0.00900,0.01076,-0.00837,0.01094,-0.00769,0.01100,-0.00700,0.00000*
%
%AMMACRO22*
4,1,40,0.00700,0.01100,-0.00700,0.01100,-0.00769,0.01094,-0.00837,0.01076,-0.00900,0.01046,-0.00957,0.01006,-0.01006,0.00957,-0.01046,0.00900,-0.01076,0.00837,-0.01094,0.00770,-0.01100,0.00700,-0.01100,-0.00700,-0.01094,-0.00769,-0.01076,-0.00837,-0.01046,-0.00900,-0.01006,-0.00957,-0.00957,-0.01006,-0.00900,-0.01046,-0.00837,-0.01076,-0.00769,-0.01094,-0.00700,-0.01100,0.00700,-0.01100,0.00770,-0.01094,0.00837,-0.01076,0.00900,-0.01046,0.00957,-0.01006,0.01006,-0.00957,0.01046,-0.00900,0.01076,-0.00837,0.01094,-0.00769,0.01100,-0.00700,0.01100,0.00700,0.01094,0.00770,0.01076,0.00837,0.01046,0.00900,0.01006,0.00957,0.00957,0.01006,0.00900,0.01046,0.00837,0.01076,0.00770,0.01094,0.00700,0.01100,0.00000*
%
%AMMACRO30_1*
4,1,40,-0.01200,0.00800,-0.01200,-0.00800,-0.01194,-0.00869,-0.01176,-0.00937,-0.01146,-0.01000,-0.01106,-0.01057,-0.01057,-0.01106,-0.01000,-0.01146,-0.00937,-0.01176,-0.00869,-0.01194,-0.00800,-0.01200,0.00800,-0.01200,0.00870,-0.01194,0.00937,-0.01176,0.01000,-0.01146,0.01057,-0.01106,0.01106,-0.01057,0.01146,-0.01000,0.01176,-0.00937,0.01194,-0.00869,0.01200,-0.00800,0.01200,0.00800,0.01194,0.00870,0.01176,0.00937,0.01146,0.01000,0.01106,0.01057,0.01057,0.01106,0.01000,0.01146,0.00937,0.01176,0.00870,0.01194,0.00800,0.01200,-0.00800,0.01200,-0.00869,0.01194,-0.00937,0.01176,-0.01000,0.01146,-0.01057,0.01106,-0.01106,0.01057,-0.01146,0.01000,-0.01176,0.00937,-0.01194,0.00870,-0.01200,0.00800,0.00000*
%
%AMMACRO63*
4,1,40,0.00800,0.01200,-0.00800,0.01200,-0.00869,0.01194,-0.00937,0.01176,-0.01000,0.01146,-0.01057,0.01106,-0.01106,0.01057,-0.01146,0.01000,-0.01176,0.00937,-0.01194,0.00870,-0.01200,0.00800,-0.01200,-0.00800,-0.01194,-0.00869,-0.01176,-0.00937,-0.01146,-0.01000,-0.01106,-0.01057,-0.01057,-0.01106,-0.01000,-0.01146,-0.00937,-0.01176,-0.00869,-0.01194,-0.00800,-0.01200,0.00800,-0.01200,0.00870,-0.01194,0.00937,-0.01176,0.01000,-0.01146,0.01057,-0.01106,0.01106,-0.01057,0.01146,-0.01000,0.01176,-0.00937,0.01194,-0.00869,0.01200,-0.00800,0.01200,0.00800,0.01194,0.00870,0.01176,0.00937,0.01146,0.01000,0.01106,0.01057,0.01057,0.01106,0.01000,0.01146,0.00937,0.01176,0.00870,0.01194,0.00800,0.01200,0.00000*
%
%AMMACRO47*
4,1,40,-0.01300,-0.01700,0.01300,-0.01700,0.01370,-0.01694,0.01437,-0.01676,0.01500,-0.01646,0.01557,-0.01606,0.01606,-0.01557,0.01646,-0.01500,0.01676,-0.01437,0.01694,-0.01369,0.01700,-0.01300,0.01700,0.01300,0.01694,0.01370,0.01676,0.01437,0.01646,0.01500,0.01606,0.01557,0.01557,0.01606,0.01500,0.01646,0.01437,0.01676,0.01370,0.01694,0.01300,0.01700,-0.01300,0.01700,-0.01369,0.01694,-0.01437,0.01676,-0.01500,0.01646,-0.01557,0.01606,-0.01606,0.01557,-0.01646,0.01500,-0.01676,0.01437,-0.01694,0.01370,-0.01700,0.01300,-0.01700,-0.01300,-0.01694,-0.01369,-0.01676,-0.01437,-0.01646,-0.01500,-0.01606,-0.01557,-0.01557,-0.01606,-0.01500,-0.01646,-0.01437,-0.01676,-0.01369,-0.01694,-0.01300,-0.01700,0.00000*
%
%AMMACRO59*
4,1,40,-0.01700,0.01300,-0.01700,-0.01300,-0.01694,-0.01369,-0.01676,-0.01437,-0.01646,-0.01500,-0.01606,-0.01557,-0.01557,-0.01606,-0.01500,-0.01646,-0.01437,-0.01676,-0.01369,-0.01694,-0.01300,-0.01700,0.01300,-0.01700,0.01370,-0.01694,0.01437,-0.01676,0.01500,-0.01646,0.01557,-0.01606,0.01606,-0.01557,0.01646,-0.01500,0.01676,-0.01437,0.01694,-0.01369,0.01700,-0.01300,0.01700,0.01300,0.01694,0.01370,0.01676,0.01437,0.01646,0.01500,0.01606,0.01557,0.01557,0.01606,0.01500,0.01646,0.01437,0.01676,0.01370,0.01694,0.01300,0.01700,-0.01300,0.01700,-0.01369,0.01694,-0.01437,0.01676,-0.01500,0.01646,-0.01557,0.01606,-0.01606,0.01557,-0.01646,0.01500,-0.01676,0.01437,-0.01694,0.01370,-0.01700,0.01300,0.00000*
%
%AMMACRO42_1*
4,1,40,-0.00800,-0.01200,0.00800,-0.01200,0.00870,-0.01194,0.00937,-0.01176,0.01000,-0.01146,0.01057,-0.01106,0.01106,-0.01057,0.01146,-0.01000,0.01176,-0.00937,0.01194,-0.00869,0.01200,-0.00800,0.01200,0.00800,0.01194,0.00870,0.01176,0.00937,0.01146,0.01000,0.01106,0.01057,0.01057,0.01106,0.01000,0.01146,0.00937,0.01176,0.00870,0.01194,0.00800,0.01200,-0.00800,0.01200,-0.00869,0.01194,-0.00937,0.01176,-0.01000,0.01146,-0.01057,0.01106,-0.01106,0.01057,-0.01146,0.01000,-0.01176,0.00937,-0.01194,0.00870,-0.01200,0.00800,-0.01200,-0.00800,-0.01194,-0.00869,-0.01176,-0.00937,-0.01146,-0.01000,-0.01106,-0.01057,-0.01057,-0.01106,-0.01000,-0.01146,-0.00937,-0.01176,-0.00869,-0.01194,-0.00800,-0.01200,0.00000*
%
%AMMACRO28_1*
4,1,40,0.01200,-0.00800,0.01200,0.00800,0.01194,0.00870,0.01176,0.00937,0.01146,0.01000,0.01106,0.01057,0.01057,0.01106,0.01000,0.01146,0.00937,0.01176,0.00870,0.01194,0.00800,0.01200,-0.00800,0.01200,-0.00869,0.01194,-0.00937,0.01176,-0.01000,0.01146,-0.01057,0.01106,-0.01106,0.01057,-0.01146,0.01000,-0.01176,0.00937,-0.01194,0.00870,-0.01200,0.00800,-0.01200,-0.00800,-0.01194,-0.00869,-0.01176,-0.00937,-0.01146,-0.01000,-0.01106,-0.01057,-0.01057,-0.01106,-0.01000,-0.01146,-0.00937,-0.01176,-0.00869,-0.01194,-0.00800,-0.01200,0.00800,-0.01200,0.00870,-0.01194,0.00937,-0.01176,0.01000,-0.01146,0.01057,-0.01106,0.01106,-0.01057,0.01146,-0.01000,0.01176,-0.00937,0.01194,-0.00869,0.01200,-0.00800,0.00000*
%
%AMMACRO20_1*
4,1,40,-0.00700,-0.01100,0.00700,-0.01100,0.00770,-0.01094,0.00837,-0.01076,0.00900,-0.01046,0.00957,-0.01006,0.01006,-0.00957,0.01046,-0.00900,0.01076,-0.00837,0.01094,-0.00769,0.01100,-0.00700,0.01100,0.00700,0.01094,0.00770,0.01076,0.00837,0.01046,0.00900,0.01006,0.00957,0.00957,0.01006,0.00900,0.01046,0.00837,0.01076,0.00770,0.01094,0.00700,0.01100,-0.00700,0.01100,-0.00769,0.01094,-0.00837,0.01076,-0.00900,0.01046,-0.00957,0.01006,-0.01006,0.00957,-0.01046,0.00900,-0.01076,0.00837,-0.01094,0.00770,-0.01100,0.00700,-0.01100,-0.00700,-0.01094,-0.00769,-0.01076,-0.00837,-0.01046,-0.00900,-0.01006,-0.00957,-0.00957,-0.01006,-0.00900,-0.01046,-0.00837,-0.01076,-0.00769,-0.01094,-0.00700,-0.01100,0.00000*
%
%AMMACRO18_1*
4,1,40,-0.01100,0.00700,-0.01100,-0.00700,-0.01094,-0.00769,-0.01076,-0.00837,-0.01046,-0.00900,-0.01006,-0.00957,-0.00957,-0.01006,-0.00900,-0.01046,-0.00837,-0.01076,-0.00769,-0.01094,-0.00700,-0.01100,0.00700,-0.01100,0.00770,-0.01094,0.00837,-0.01076,0.00900,-0.01046,0.00957,-0.01006,0.01006,-0.00957,0.01046,-0.00900,0.01076,-0.00837,0.01094,-0.00769,0.01100,-0.00700,0.01100,0.00700,0.01094,0.00770,0.01076,0.00837,0.01046,0.00900,0.01006,0.00957,0.00957,0.01006,0.00900,0.01046,0.00837,0.01076,0.00770,0.01094,0.00700,0.01100,-0.00700,0.01100,-0.00769,0.01094,-0.00837,0.01076,-0.00900,0.01046,-0.00957,0.01006,-0.01006,0.00957,-0.01046,0.00900,-0.01076,0.00837,-0.01094,0.00770,-0.01100,0.00700,0.00000*
%
%AMMACRO66*
4,1,3,0.02500,0.01250,0.00000,-0.01250,-0.02500,0.01250,0.02500,0.01250,0.00000*
%
%AMMACRO59_1*
4,1,3,0.00000,-0.01250,-0.02500,0.01250,0.02500,0.01250,0.00000,-0.01250,0.00000*
%
%AMMACRO52*
4,1,40,0.00800,0.01200,-0.00800,0.01200,-0.00869,0.01194,-0.00937,0.01176,-0.01000,0.01146,-0.01057,0.01106,-0.01106,0.01057,-0.01146,0.01000,-0.01176,0.00937,-0.01194,0.00870,-0.01200,0.00800,-0.01200,-0.00800,-0.01194,-0.00869,-0.01176,-0.00937,-0.01146,-0.01000,-0.01106,-0.01057,-0.01057,-0.01106,-0.01000,-0.01146,-0.00937,-0.01176,-0.00869,-0.01194,-0.00800,-0.01200,0.00800,-0.01200,0.00870,-0.01194,0.00937,-0.01176,0.01000,-0.01146,0.01057,-0.01106,0.01106,-0.01057,0.01146,-0.01000,0.01176,-0.00937,0.01194,-0.00869,0.01200,-0.00800,0.01200,0.00800,0.01194,0.00870,0.01176,0.00937,0.01146,0.01000,0.01106,0.01057,0.01057,0.01106,0.01000,0.01146,0.00937,0.01176,0.00870,0.01194,0.00800,0.01200,0.00000*
%
%AMMACRO64*
4,1,20,0.06350,-0.10750,0.04900,-0.10750,0.04900,-0.11800,0.03950,-0.11800,0.03950,-0.10750,-0.03950,-0.10750,-0.03950,-0.11800,-0.04900,-0.11800,-0.04900,-0.10750,-0.06350,-0.10750,-0.06350,0.10750,-0.04900,0.10750,-0.04900,0.11800,-0.03950,0.11800,-0.03950,0.10750,0.03950,0.10750,0.03950,0.11800,0.04900,0.11800,0.04900,0.10750,0.06350,0.10750,0.06350,-0.10750,0.00000*
%
%AMMACRO38*
4,1,40,-0.01300,-0.01700,0.01300,-0.01700,0.01370,-0.01694,0.01437,-0.01676,0.01500,-0.01646,0.01557,-0.01606,0.01606,-0.01557,0.01646,-0.01500,0.01676,-0.01437,0.01694,-0.01369,0.01700,-0.01300,0.01700,0.01300,0.01694,0.01370,0.01676,0.01437,0.01646,0.01500,0.01606,0.01557,0.01557,0.01606,0.01500,0.01646,0.01437,0.01676,0.01370,0.01694,0.01300,0.01700,-0.01300,0.01700,-0.01369,0.01694,-0.01437,0.01676,-0.01500,0.01646,-0.01557,0.01606,-0.01606,0.01557,-0.01646,0.01500,-0.01676,0.01437,-0.01694,0.01370,-0.01700,0.01300,-0.01700,-0.01300,-0.01694,-0.01369,-0.01676,-0.01437,-0.01646,-0.01500,-0.01606,-0.01557,-0.01557,-0.01606,-0.01500,-0.01646,-0.01437,-0.01676,-0.01369,-0.01694,-0.01300,-0.01700,0.00000*
%
%AMMACRO55*
4,1,3,-0.02500,-0.01250,0.00000,0.01250,0.02500,-0.01250,-0.02500,-0.01250,0.00000*
%
%AMMACRO65*
4,1,3,0.00000,0.01250,0.02500,-0.01250,-0.02500,-0.01250,0.00000,0.01250,0.00000*
%
%AMMACRO58*
4,1,12,-0.04050,0.04050,-0.01300,0.04050,-0.01300,0.07000,0.01300,0.07000,0.01300,0.04050,0.04050,0.04050,0.04050,-0.04050,0.01300,-0.04050,0.01300,-0.07000,-0.01300,-0.07000,-0.01300,-0.04050,-0.04050,-0.04050,-0.04050,0.04050,0.00000*
%
%AMMACRO20_1_180*
4,1,40,0.00700,0.01100,-0.00700,0.01100,-0.00770,0.01094,-0.00837,0.01076,-0.00900,0.01046,-0.00957,0.01006,-0.01006,0.00957,-0.01046,0.00900,-0.01076,0.00837,-0.01094,0.00769,-0.01100,0.00700,-0.01100,-0.00700,-0.01094,-0.00770,-0.01076,-0.00837,-0.01046,-0.00900,-0.01006,-0.00957,-0.00957,-0.01006,-0.00900,-0.01046,-0.00837,-0.01076,-0.00770,-0.01094,-0.00700,-0.01100,0.00700,-0.01100,0.00769,-0.01094,0.00837,-0.01076,0.00900,-0.01046,0.00957,-0.01006,0.01006,-0.00957,0.01046,-0.00900,0.01076,-0.00837,0.01094,-0.00770,0.01100,-0.00700,0.01100,0.00700,0.01094,0.00769,0.01076,0.00837,0.01046,0.00900,0.01006,0.00957,0.00957,0.01006,0.00900,0.01046,0.00837,0.01076,0.00769,0.01094,0.00700,0.01100,0.00000*
%
%AMMACRO30_1_180*
4,1,40,0.01200,-0.00800,0.01200,0.00800,0.01194,0.00869,0.01176,0.00937,0.01146,0.01000,0.01106,0.01057,0.01057,0.01106,0.01000,0.01146,0.00937,0.01176,0.00869,0.01194,0.00800,0.01200,-0.00800,0.01200,-0.00870,0.01194,-0.00937,0.01176,-0.01000,0.01146,-0.01057,0.01106,-0.01106,0.01057,-0.01146,0.01000,-0.01176,0.00937,-0.01194,0.00869,-0.01200,0.00800,-0.01200,-0.00800,-0.01194,-0.00870,-0.01176,-0.00937,-0.01146,-0.01000,-0.01106,-0.01057,-0.01057,-0.01106,-0.01000,-0.01146,-0.00937,-0.01176,-0.00870,-0.01194,-0.00800,-0.01200,0.00800,-0.01200,0.00869,-0.01194,0.00937,-0.01176,0.01000,-0.01146,0.01057,-0.01106,0.01106,-0.01057,0.01146,-0.01000,0.01176,-0.00937,0.01194,-0.00870,0.01200,-0.00800,0.00000*
%
%AMMACRO28_1_180*
4,1,40,-0.01200,0.00800,-0.01200,-0.00800,-0.01194,-0.00870,-0.01176,-0.00937,-0.01146,-0.01000,-0.01106,-0.01057,-0.01057,-0.01106,-0.01000,-0.01146,-0.00937,-0.01176,-0.00870,-0.01194,-0.00800,-0.01200,0.00800,-0.01200,0.00869,-0.01194,0.00937,-0.01176,0.01000,-0.01146,0.01057,-0.01106,0.01106,-0.01057,0.01146,-0.01000,0.01176,-0.00937,0.01194,-0.00870,0.01200,-0.00800,0.01200,0.00800,0.01194,0.00869,0.01176,0.00937,0.01146,0.01000,0.01106,0.01057,0.01057,0.01106,0.01000,0.01146,0.00937,0.01176,0.00869,0.01194,0.00800,0.01200,-0.00800,0.01200,-0.00870,0.01194,-0.00937,0.01176,-0.01000,0.01146,-0.01057,0.01106,-0.01106,0.01057,-0.01146,0.01000,-0.01176,0.00937,-0.01194,0.00869,-0.01200,0.00800,0.00000*
%
%AMMACRO44_1_180*
4,1,40,-0.01300,-0.01700,0.01300,-0.01700,0.01369,-0.01694,0.01437,-0.01676,0.01500,-0.01646,0.01557,-0.01606,0.01606,-0.01557,0.01646,-0.01500,0.01676,-0.01437,0.01694,-0.01370,0.01700,-0.01300,0.01700,0.01300,0.01694,0.01369,0.01676,0.01437,0.01646,0.01500,0.01606,0.01557,0.01557,0.01606,0.01500,0.01646,0.01437,0.01676,0.01369,0.01694,0.01300,0.01700,-0.01300,0.01700,-0.01370,0.01694,-0.01437,0.01676,-0.01500,0.01646,-0.01557,0.01606,-0.01606,0.01557,-0.01646,0.01500,-0.01676,0.01437,-0.01694,0.01369,-0.01700,0.01300,-0.01700,-0.01300,-0.01694,-0.01370,-0.01676,-0.01437,-0.01646,-0.01500,-0.01606,-0.01557,-0.01557,-0.01606,-0.01500,-0.01646,-0.01437,-0.01676,-0.01370,-0.01694,-0.01300,-0.01700,0.00000*
%
%AMMACRO22_180*
4,1,40,-0.00700,-0.01100,0.00700,-0.01100,0.00769,-0.01094,0.00837,-0.01076,0.00900,-0.01046,0.00957,-0.01006,0.01006,-0.00957,0.01046,-0.00900,0.01076,-0.00837,0.01094,-0.00770,0.01100,-0.00700,0.01100,0.00700,0.01094,0.00769,0.01076,0.00837,0.01046,0.00900,0.01006,0.00957,0.00957,0.01006,0.00900,0.01046,0.00837,0.01076,0.00769,0.01094,0.00700,0.01100,-0.00700,0.01100,-0.00770,0.01094,-0.00837,0.01076,-0.00900,0.01046,-0.00957,0.01006,-0.01006,0.00957,-0.01046,0.00900,-0.01076,0.00837,-0.01094,0.00769,-0.01100,0.00700,-0.01100,-0.00700,-0.01094,-0.00770,-0.01076,-0.00837,-0.01046,-0.00900,-0.01006,-0.00957,-0.00957,-0.01006,-0.00900,-0.01046,-0.00837,-0.01076,-0.00770,-0.01094,-0.00700,-0.01100,0.00000*
%
%AMMACRO42_1_180*
4,1,40,0.00800,0.01200,-0.00800,0.01200,-0.00870,0.01194,-0.00937,0.01176,-0.01000,0.01146,-0.01057,0.01106,-0.01106,0.01057,-0.01146,0.01000,-0.01176,0.00937,-0.01194,0.00869,-0.01200,0.00800,-0.01200,-0.00800,-0.01194,-0.00870,-0.01176,-0.00937,-0.01146,-0.01000,-0.01106,-0.01057,-0.01057,-0.01106,-0.01000,-0.01146,-0.00937,-0.01176,-0.00870,-0.01194,-0.00800,-0.01200,0.00800,-0.01200,0.00869,-0.01194,0.00937,-0.01176,0.01000,-0.01146,0.01057,-0.01106,0.01106,-0.01057,0.01146,-0.01000,0.01176,-0.00937,0.01194,-0.00870,0.01200,-0.00800,0.01200,0.00800,0.01194,0.00869,0.01176,0.00937,0.01146,0.01000,0.01106,0.01057,0.01057,0.01106,0.01000,0.01146,0.00937,0.01176,0.00869,0.01194,0.00800,0.01200,0.00000*
%
%AMMACRO50_1_180*
4,1,40,-0.01700,0.01300,-0.01700,-0.01300,-0.01694,-0.01370,-0.01676,-0.01437,-0.01646,-0.01500,-0.01606,-0.01557,-0.01557,-0.01606,-0.01500,-0.01646,-0.01437,-0.01676,-0.01370,-0.01694,-0.01300,-0.01700,0.01300,-0.01700,0.01369,-0.01694,0.01437,-0.01676,0.01500,-0.01646,0.01557,-0.01606,0.01606,-0.01557,0.01646,-0.01500,0.01676,-0.01437,0.01694,-0.01370,0.01700,-0.01300,0.01700,0.01300,0.01694,0.01369,0.01676,0.01437,0.01646,0.01500,0.01606,0.01557,0.01557,0.01606,0.01500,0.01646,0.01437,0.01676,0.01369,0.01694,0.01300,0.01700,-0.01300,0.01700,-0.01370,0.01694,-0.01437,0.01676,-0.01500,0.01646,-0.01557,0.01606,-0.01606,0.01557,-0.01646,0.01500,-0.01676,0.01437,-0.01694,0.01369,-0.01700,0.01300,0.00000*
%
%AMMACRO24_1_180*
4,1,40,-0.01100,0.00700,-0.01100,-0.00700,-0.01094,-0.00770,-0.01076,-0.00837,-0.01046,-0.00900,-0.01006,-0.00957,-0.00957,-0.01006,-0.00900,-0.01046,-0.00837,-0.01076,-0.00770,-0.01094,-0.00700,-0.01100,0.00700,-0.01100,0.00769,-0.01094,0.00837,-0.01076,0.00900,-0.01046,0.00957,-0.01006,0.01006,-0.00957,0.01046,-0.00900,0.01076,-0.00837,0.01094,-0.00770,0.01100,-0.00700,0.01100,0.00700,0.01094,0.00769,0.01076,0.00837,0.01046,0.00900,0.01006,0.00957,0.00957,0.01006,0.00900,0.01046,0.00837,0.01076,0.00769,0.01094,0.00700,0.01100,-0.00700,0.01100,-0.00770,0.01094,-0.00837,0.01076,-0.00900,0.01046,-0.00957,0.01006,-0.01006,0.00957,-0.01046,0.00900,-0.01076,0.00837,-0.01094,0.00769,-0.01100,0.00700,0.00000*
%
%AMMACRO18_1_180*
4,1,40,0.01100,-0.00700,0.01100,0.00700,0.01094,0.00769,0.01076,0.00837,0.01046,0.00900,0.01006,0.00957,0.00957,0.01006,0.00900,0.01046,0.00837,0.01076,0.00769,0.01094,0.00700,0.01100,-0.00700,0.01100,-0.00770,0.01094,-0.00837,0.01076,-0.00900,0.01046,-0.00957,0.01006,-0.01006,0.00957,-0.01046,0.00900,-0.01076,0.00837,-0.01094,0.00769,-0.01100,0.00700,-0.01100,-0.00700,-0.01094,-0.00770,-0.01076,-0.00837,-0.01046,-0.00900,-0.01006,-0.00957,-0.00957,-0.01006,-0.00900,-0.01046,-0.00837,-0.01076,-0.00770,-0.01094,-0.00700,-0.01100,0.00700,-0.01100,0.00769,-0.01094,0.00837,-0.01076,0.00900,-0.01046,0.00957,-0.01006,0.01006,-0.00957,0.01046,-0.00900,0.01076,-0.00837,0.01094,-0.00770,0.01100,-0.00700,0.00000*
%
%AMMACRO63_180*
4,1,40,-0.00800,-0.01200,0.00800,-0.01200,0.00869,-0.01194,0.00937,-0.01176,0.01000,-0.01146,0.01057,-0.01106,0.01106,-0.01057,0.01146,-0.01000,0.01176,-0.00937,0.01194,-0.00870,0.01200,-0.00800,0.01200,0.00800,0.01194,0.00869,0.01176,0.00937,0.01146,0.01000,0.01106,0.01057,0.01057,0.01106,0.01000,0.01146,0.00937,0.01176,0.00869,0.01194,0.00800,0.01200,-0.00800,0.01200,-0.00870,0.01194,-0.00937,0.01176,-0.01000,0.01146,-0.01057,0.01106,-0.01106,0.01057,-0.01146,0.01000,-0.01176,0.00937,-0.01194,0.00869,-0.01200,0.00800,-0.01200,-0.00800,-0.01194,-0.00870,-0.01176,-0.00937,-0.01146,-0.01000,-0.01106,-0.01057,-0.01057,-0.01106,-0.01000,-0.01146,-0.00937,-0.01176,-0.00870,-0.01194,-0.00800,-0.01200,0.00000*
%
%AMMACRO47_180*
4,1,40,0.01300,0.01700,-0.01300,0.01700,-0.01370,0.01694,-0.01437,0.01676,-0.01500,0.01646,-0.01557,0.01606,-0.01606,0.01557,-0.01646,0.01500,-0.01676,0.01437,-0.01694,0.01369,-0.01700,0.01300,-0.01700,-0.01300,-0.01694,-0.01370,-0.01676,-0.01437,-0.01646,-0.01500,-0.01606,-0.01557,-0.01557,-0.01606,-0.01500,-0.01646,-0.01437,-0.01676,-0.01370,-0.01694,-0.01300,-0.01700,0.01300,-0.01700,0.01369,-0.01694,0.01437,-0.01676,0.01500,-0.01646,0.01557,-0.01606,0.01606,-0.01557,0.01646,-0.01500,0.01676,-0.01437,0.01694,-0.01370,0.01700,-0.01300,0.01700,0.01300,0.01694,0.01369,0.01676,0.01437,0.01646,0.01500,0.01606,0.01557,0.01557,0.01606,0.01500,0.01646,0.01437,0.01676,0.01369,0.01694,0.01300,0.01700,0.00000*
%
%AMMACRO59_180*
4,1,40,0.01700,-0.01300,0.01700,0.01300,0.01694,0.01369,0.01676,0.01437,0.01646,0.01500,0.01606,0.01557,0.01557,0.01606,0.01500,0.01646,0.01437,0.01676,0.01369,0.01694,0.01300,0.01700,-0.01300,0.01700,-0.01370,0.01694,-0.01437,0.01676,-0.01500,0.01646,-0.01557,0.01606,-0.01606,0.01557,-0.01646,0.01500,-0.01676,0.01437,-0.01694,0.01369,-0.01700,0.01300,-0.01700,-0.01300,-0.01694,-0.01370,-0.01676,-0.01437,-0.01646,-0.01500,-0.01606,-0.01557,-0.01557,-0.01606,-0.01500,-0.01646,-0.01437,-0.01676,-0.01370,-0.01694,-0.01300,-0.01700,0.01300,-0.01700,0.01369,-0.01694,0.01437,-0.01676,0.01500,-0.01646,0.01557,-0.01606,0.01606,-0.01557,0.01646,-0.01500,0.01676,-0.01437,0.01694,-0.01370,0.01700,-0.01300,0.00000*
%
%AMMACRO52_180*
4,1,40,-0.00800,-0.01200,0.00800,-0.01200,0.00869,-0.01194,0.00937,-0.01176,0.01000,-0.01146,0.01057,-0.01106,0.01106,-0.01057,0.01146,-0.01000,0.01176,-0.00937,0.01194,-0.00870,0.01200,-0.00800,0.01200,0.00800,0.01194,0.00869,0.01176,0.00937,0.01146,0.01000,0.01106,0.01057,0.01057,0.01106,0.01000,0.01146,0.00937,0.01176,0.00869,0.01194,0.00800,0.01200,-0.00800,0.01200,-0.00870,0.01194,-0.00937,0.01176,-0.01000,0.01146,-0.01057,0.01106,-0.01106,0.01057,-0.01146,0.01000,-0.01176,0.00937,-0.01194,0.00869,-0.01200,0.00800,-0.01200,-0.00800,-0.01194,-0.00870,-0.01176,-0.00937,-0.01146,-0.01000,-0.01106,-0.01057,-0.01057,-0.01106,-0.01000,-0.01146,-0.00937,-0.01176,-0.00870,-0.01194,-0.00800,-0.01200,0.00000*
%
%AMMACRO55_180*
4,1,3,0.02500,0.01250,0.00000,-0.01250,-0.02500,0.01250,0.02500,0.01250,0.00000*
%
%AMMACRO64_180*
4,1,20,-0.06350,0.10750,-0.04900,0.10750,-0.04900,0.11800,-0.03950,0.11800,-0.03950,0.10750,0.03950,0.10750,0.03950,0.11800,0.04900,0.11800,0.04900,0.10750,0.06350,0.10750,0.06350,-0.10750,0.04900,-0.10750,0.04900,-0.11800,0.03950,-0.11800,0.03950,-0.10750,-0.03950,-0.10750,-0.03950,-0.11800,-0.04900,-0.11800,-0.04900,-0.10750,-0.06350,-0.10750,-0.06350,0.10750,0.00000*
%
%AMMACRO65_180*
4,1,3,0.00000,-0.01250,-0.02500,0.01250,0.02500,0.01250,0.00000,-0.01250,0.00000*
%
%AMMACRO38_180*
4,1,40,0.01300,0.01700,-0.01300,0.01700,-0.01370,0.01694,-0.01437,0.01676,-0.01500,0.01646,-0.01557,0.01606,-0.01606,0.01557,-0.01646,0.01500,-0.01676,0.01437,-0.01694,0.01369,-0.01700,0.01300,-0.01700,-0.01300,-0.01694,-0.01370,-0.01676,-0.01437,-0.01646,-0.01500,-0.01606,-0.01557,-0.01557,-0.01606,-0.01500,-0.01646,-0.01437,-0.01676,-0.01370,-0.01694,-0.01300,-0.01700,0.01300,-0.01700,0.01369,-0.01694,0.01437,-0.01676,0.01500,-0.01646,0.01557,-0.01606,0.01606,-0.01557,0.01646,-0.01500,0.01676,-0.01437,0.01694,-0.01370,0.01700,-0.01300,0.01700,0.01300,0.01694,0.01369,0.01676,0.01437,0.01646,0.01500,0.01606,0.01557,0.01557,0.01606,0.01500,0.01646,0.01437,0.01676,0.01369,0.01694,0.01300,0.01700,0.00000*
%
%AMMACRO66_180*
4,1,3,-0.02500,-0.01250,0.00000,0.01250,0.02500,-0.01250,-0.02500,-0.01250,0.00000*
%
%AMMACRO58_180*
4,1,12,0.04050,-0.04050,0.01300,-0.04050,0.01300,-0.07000,-0.01300,-0.07000,-0.01300,-0.04050,-0.04050,-0.04050,-0.04050,0.04050,-0.01300,0.04050,-0.01300,0.07000,0.01300,0.07000,0.01300,0.04050,0.04050,0.04050,0.04050,-0.04050,0.00000*
%
%AMMACRO59_1_180*
4,1,3,0.00000,0.01250,0.02500,-0.01250,-0.02500,-0.01250,0.00000,0.01250,0.00000*
%
%ADD10C,0.00600*%
%ADD11C,0.14000*%
%ADD27R,0.06500X0.05000*%
%ADD40R,0.05500X0.04500*%
%ADD47R,0.04500X0.03000*%
%ADD56R,0.04500X0.05500*%
%ADD57R,0.12800X0.12800*%
%ADD58R,0.01400X0.04200*%
%ADD59R,0.04200X0.01400*%
%ADD61R,0.01200X0.03800*%
%ADD62R,0.03800X0.01200*%
%ADD66C,0.02000*%
%ADD78R,0.05000X0.05000*%
%ADD89MACRO50_1*%
%ADD90MACRO44_1*%
%ADD91R,0.04500X0.11000*%
%ADD92R,0.11000X0.05500*%
%ADD93R,0.06400X0.13600*%
%ADD94C,0.01800*%
%ADD95R,0.16700X0.09000*%
%ADD96MACRO24_1*%
%ADD97MACRO22*%
%ADD98MACRO30_1*%
%ADD99MACRO63*%
%ADD100MACRO47*%
%ADD102MACRO59*%
%ADD108R,0.06000X0.02000*%
%ADD109R,0.06000X0.01200*%
%ADD110O,0.07100X0.01400*%
%ADD111R,0.04000X0.01600*%
%ADD112R,0.06000X0.01400*%
%ADD113R,0.04400X0.01200*%
%ADD114R,0.01400X0.06000*%
%ADD115R,0.11400X0.12800*%
%ADD116R,0.08000X0.05000*%
%ADD117R,0.05000X0.06500*%
%ADD118R,0.07300X0.07000*%
%ADD119R,0.06500X0.02500*%
%ADD120R,0.09000X0.09000*%
%ADD122R,0.02500X0.06500*%
%ADD123R,0.08300X0.03500*%
%ADD124R,0.07400X0.05400*%
%ADD125R,0.01600X0.04800*%
%ADD126R,0.07300X0.06500*%
%ADD127R,0.09500X0.09000*%
%ADD129R,0.03800X0.09500*%
%ADD130R,0.08700X0.04700*%
%ADD131MACRO42_1*%
%ADD132MACRO28_1*%
%ADD133MACRO20_1*%
%ADD134MACRO18_1*%
%ADD141MACRO66*%
%ADD142MACRO59_1*%
%ADD143MACRO52*%
%ADD144MACRO64*%
%ADD145MACRO38*%
%ADD146MACRO55*%
%ADD147MACRO65*%
%ADD148MACRO58*%
%ADD152R,0.05500X0.04500*%
%ADD164R,0.01200X0.03800*%
%ADD168R,0.03800X0.01200*%
%ADD173R,0.06500X0.05000*%
%ADD183R,0.04500X0.05500*%
%ADD184R,0.04500X0.03000*%
%ADD186R,0.12800X0.12800*%
%ADD188R,0.01400X0.04200*%
%ADD190R,0.04200X0.01400*%
%ADD191R,0.05000X0.05000*%
%ADD204MACRO20_1_180*%
%ADD205MACRO30_1_180*%
%ADD206MACRO28_1_180*%
%ADD207MACRO44_1_180*%
%ADD208MACRO22_180*%
%ADD209MACRO42_1_180*%
%ADD210MACRO50_1_180*%
%ADD212R,0.01600X0.04800*%
%ADD214MACRO24_1_180*%
%ADD216R,0.06400X0.13600*%
%ADD217R,0.11000X0.05500*%
%ADD219R,0.03800X0.09500*%
%ADD220R,0.09500X0.09000*%
%ADD221R,0.06000X0.01200*%
%ADD222R,0.06000X0.02000*%
%ADD224MACRO18_1_180*%
%ADD225R,0.02500X0.06500*%
%ADD226R,0.09000X0.09000*%
%ADD227R,0.05000X0.06500*%
%ADD228R,0.08000X0.05000*%
%ADD229MACRO63_180*%
%ADD230R,0.07300X0.07000*%
%ADD231R,0.11400X0.12800*%
%ADD232O,0.07100X0.01400*%
%ADD233R,0.04500X0.11000*%
%ADD234R,0.07300X0.06500*%
%ADD235R,0.04400X0.01200*%
%ADD236R,0.06000X0.01400*%
%ADD237MACRO47_180*%
%ADD238R,0.16700X0.09000*%
%ADD239R,0.08700X0.04700*%
%ADD240R,0.07400X0.05400*%
%ADD241R,0.08300X0.03500*%
%ADD242R,0.06500X0.02500*%
%ADD244R,0.04000X0.01600*%
%ADD248MACRO59_180*%
%ADD250R,0.01400X0.06000*%
%ADD251MACRO52_180*%
%ADD252MACRO55_180*%
%ADD253MACRO64_180*%
%ADD254MACRO65_180*%
%ADD255MACRO38_180*%
%ADD256MACRO66_180*%
%ADD257MACRO58_180*%
%ADD258MACRO59_1_180*%
%LNTSMD.art*%
%LPD*%
G36*
X-457329Y773129D02*
G01X-449329D01*
Y768129*
X-457329*
Y773129*
G37*
G36*
X221108Y152068D02*
G01X213108D01*
Y157068*
X221108*
Y152068*
G37*
G36*
X-471829Y777629D02*
G01Y763629D01*
X-479829*
Y777629*
X-471829*
G37*
G36*
X235608Y147568D02*
G01Y161568D01*
X243608*
Y147568*
X235608*
G37*
G36*
X-402931Y728698D02*
G01X-391631D01*
Y718598*
X-402931*
Y728698*
G37*
G36*
Y741398D02*
G01X-391631D01*
Y731298*
X-402931*
Y741398*
G37*
G36*
X-389031Y728698D02*
G01X-377731D01*
Y718598*
X-389031*
Y728698*
G37*
G36*
Y741398D02*
G01X-377731D01*
Y731298*
X-389031*
Y741398*
G37*
G36*
X166710Y196499D02*
G01X155410D01*
Y206599*
X166710*
Y196499*
G37*
G36*
Y183799D02*
G01X155410D01*
Y193899*
X166710*
Y183799*
G37*
G36*
X152810Y196499D02*
G01X141510D01*
Y206599*
X152810*
Y196499*
G37*
G36*
Y183799D02*
G01X141510D01*
Y193899*
X152810*
Y183799*
G37*
G36*
X-331458Y64870D02*
G01X-314922D01*
Y56263*
X-331458*
Y64870*
G37*
G36*
Y76077D02*
G01X-314922D01*
Y67470*
X-331458*
Y76077*
G37*
G36*
Y87284D02*
G01X-314922D01*
Y78677*
X-331458*
Y87284*
G37*
G36*
Y98491D02*
G01X-314922D01*
Y89884*
X-331458*
Y98491*
G37*
G36*
Y109698D02*
G01X-314922D01*
Y101091*
X-331458*
Y109698*
G37*
G36*
Y120905D02*
G01X-314922D01*
Y112298*
X-331458*
Y120905*
G37*
G36*
X95237Y860327D02*
G01X78701D01*
Y868934*
X95237*
Y860327*
G37*
G36*
Y849120D02*
G01X78701D01*
Y857727*
X95237*
Y849120*
G37*
G36*
Y837913D02*
G01X78701D01*
Y846520*
X95237*
Y837913*
G37*
G36*
Y826706D02*
G01X78701D01*
Y835313*
X95237*
Y826706*
G37*
G36*
Y815499D02*
G01X78701D01*
Y824106*
X95237*
Y815499*
G37*
G36*
Y804292D02*
G01X78701D01*
Y812899*
X95237*
Y804292*
G37*
G36*
X-336514Y53663D02*
G01X-314922D01*
Y43427*
X-336514*
Y53663*
G37*
G36*
Y133739D02*
G01X-314922D01*
Y123503*
X-336514*
Y133739*
G37*
G36*
X100293Y871534D02*
G01X78701D01*
Y881770*
X100293*
Y871534*
G37*
G36*
Y791458D02*
G01X78701D01*
Y801694*
X100293*
Y791458*
G37*
G36*
X-395564Y133739D02*
G01X-354739D01*
Y123503*
X-376764*
Y125485*
X-376699Y125863*
X-376667Y126246*
X-376669Y126630*
X-376704Y127012*
X-376773Y127390*
X-376874Y127760*
X-377006Y128120*
X-377170Y128467*
X-377364Y128799*
X-377585Y129112*
X-377833Y129405*
X-378106Y129675*
X-378401Y129921*
X-378717Y130140*
X-379050Y130330*
X-379398Y130491*
X-379760Y130620*
X-380131Y130718*
X-380509Y130783*
X-380892Y130815*
X-381276Y130813*
X-381658Y130778*
X-382036Y130709*
X-382406Y130608*
X-382766Y130476*
X-383113Y130312*
X-383445Y130118*
X-383758Y129897*
X-384051Y129649*
X-384321Y129376*
X-384567Y129081*
X-384786Y128765*
X-384976Y128432*
X-385137Y128084*
X-385266Y127722*
X-385364Y127351*
X-385429Y126973*
X-385461Y126590*
X-385459Y126206*
X-385424Y125824*
X-385364Y125485*
Y123503*
X-395564*
Y133739*
G37*
G36*
X159343Y791458D02*
G01X118518D01*
Y801694*
X140543*
Y799712*
X140478Y799334*
X140446Y798951*
X140448Y798567*
X140483Y798185*
X140552Y797807*
X140653Y797437*
X140785Y797077*
X140949Y796730*
X141143Y796398*
X141364Y796085*
X141612Y795792*
X141885Y795522*
X142180Y795276*
X142496Y795057*
X142829Y794867*
X143177Y794706*
X143539Y794577*
X143910Y794479*
X144288Y794414*
X144671Y794382*
X145055Y794384*
X145437Y794419*
X145815Y794488*
X146185Y794589*
X146545Y794721*
X146892Y794885*
X147224Y795079*
X147537Y795300*
X147830Y795548*
X148100Y795821*
X148346Y796116*
X148565Y796432*
X148755Y796765*
X148916Y797113*
X149045Y797475*
X149143Y797846*
X149208Y798224*
X149240Y798607*
X149238Y798991*
X149203Y799373*
X149143Y799712*
Y801694*
X159343*
Y791458*
G37*
G36*
X-395589Y53663D02*
G01X-385364D01*
Y51681*
X-385429Y51303*
X-385461Y50920*
X-385459Y50536*
X-385424Y50154*
X-385355Y49776*
X-385254Y49406*
X-385121Y49046*
X-384958Y48699*
X-384764Y48367*
X-384543Y48054*
X-384295Y47761*
X-384022Y47491*
X-383727Y47245*
X-383411Y47026*
X-383078Y46836*
X-382730Y46675*
X-382368Y46546*
X-381997Y46448*
X-381619Y46383*
X-381236Y46351*
X-380852Y46353*
X-380470Y46388*
X-380092Y46457*
X-379722Y46558*
X-379362Y46691*
X-379015Y46854*
X-378683Y47048*
X-378370Y47269*
X-378077Y47517*
X-377807Y47790*
X-377561Y48085*
X-377342Y48401*
X-377152Y48734*
X-376991Y49082*
X-376862Y49444*
X-376764Y49815*
X-376699Y50193*
X-376667Y50576*
X-376669Y50960*
X-376704Y51342*
X-376764Y51681*
Y53663*
X-354739*
Y43427*
X-395589*
Y53663*
G37*
G36*
X159368Y871534D02*
G01X149143D01*
Y873516*
X149208Y873894*
X149240Y874277*
X149238Y874661*
X149203Y875043*
X149134Y875421*
X149033Y875791*
X148900Y876151*
X148737Y876498*
X148543Y876830*
X148322Y877143*
X148074Y877436*
X147801Y877706*
X147506Y877952*
X147190Y878171*
X146857Y878361*
X146509Y878522*
X146147Y878651*
X145776Y878749*
X145398Y878814*
X145015Y878846*
X144631Y878844*
X144249Y878809*
X143871Y878740*
X143501Y878639*
X143141Y878506*
X142794Y878343*
X142462Y878149*
X142149Y877928*
X141856Y877680*
X141586Y877407*
X141340Y877112*
X141121Y876796*
X140931Y876463*
X140770Y876115*
X140641Y875753*
X140543Y875382*
X140478Y875004*
X140446Y874621*
X140448Y874237*
X140483Y873855*
X140543Y873516*
Y871534*
X118518*
Y881770*
X159368*
Y871534*
G37*
G36*
X-413789Y53663D02*
G01Y43427D01*
X-434922*
Y70671*
X-426614*
Y53663*
X-413789*
G37*
G36*
X177568Y871534D02*
G01Y881770D01*
X198701*
Y854526*
X190393*
Y871534*
X177568*
G37*
G36*
X-413814Y133739D02*
G01Y123503D01*
X-426614*
Y104921*
X-434922*
Y133739*
X-413814*
G37*
G36*
X177593Y791458D02*
G01Y801694D01*
X190393*
Y820276*
X198701*
Y791458*
X177593*
G37*
G54D11*
G55*
X-1011811Y-15748D03*
Y940945*
X775591Y-15748*
Y940944*
G54D96*
G55*
X63000Y99900D03*
X67300*
X50963Y378983*
X46763Y394483*
X50830Y394489*
X50963Y386783*
X46763Y387083*
X61563Y370883*
X60122Y751061*
X107783Y83161*
X91178Y207933*
X80326Y655588*
X79967Y640094*
X80653Y755247*
X80415Y772933*
X208612Y78030*
X219504Y178170*
X177087Y172033*
X185215Y414633*
X185266Y489643*
X219303Y744714*
X229613Y61498*
X223817Y178208*
X235414Y214313*
X238000Y414700*
X227900Y414600*
X232100*
X240662Y383684*
X241728Y356756*
X237455Y367855*
X242700Y436600*
X223658Y744714*
X234524Y771383*
X447090Y500442*
X504027Y409475*
X504094Y401932*
X503981Y417019*
X525463Y542533*
X665909Y462723*
X649409Y479323*
X670009Y458623*
X653509Y475023*
X711409Y450523*
X650700Y529500*
X689190Y768106*
X715509Y454523*
X732109Y471123*
X727909Y466823*
G54D78*
G55*
X-944882Y-17185D03*
Y942382*
X43000Y354200*
X245200Y551000*
X708683Y-17218*
G54D129*
G55*
X70675Y134665D03*
X54925*
X70675Y155935*
X54925*
G54D56*
G55*
X33253Y486907D03*
X25653*
X33250Y479024*
X25650*
X245837Y83579*
X253437*
X302287Y456235*
X294687*
X653800Y520900*
X646200*
X653819Y513168*
X646219*
G54D109*
G55*
X58059Y84803D03*
Y86768*
Y88738*
Y90708*
Y92673*
X74359*
Y90708*
Y88738*
Y86768*
Y84803*
X107899Y197156*
Y195191*
Y193221*
Y191251*
Y189286*
X91599*
Y191251*
Y193221*
Y195191*
Y197156*
X82163Y244428*
Y246398*
Y248368*
Y250338*
Y252308*
Y254278*
Y256248*
Y258218*
Y260188*
Y262158*
Y264128*
Y266098*
Y268068*
Y270038*
Y272008*
Y273978*
Y275948*
Y277918*
Y279888*
Y281858*
Y283828*
Y285798*
Y287768*
Y289738*
X157763Y273978*
Y272008*
Y270038*
Y268068*
Y266098*
Y264128*
Y262158*
Y260188*
Y258218*
Y256248*
Y254278*
Y252308*
Y250338*
Y248368*
Y246398*
Y244428*
Y289738*
Y287768*
Y285798*
Y283828*
Y281858*
Y279888*
Y277918*
Y275948*
X476320Y508067*
Y506102*
Y504132*
Y502162*
Y500197*
X460020*
Y502162*
Y504132*
Y506102*
Y508067*
G54D132*
G55*
X27990Y497166D03*
X80800Y199800*
X99041Y203600*
X219061Y461171*
X219034Y464704*
X233200Y454700*
X298500Y466600*
X478728Y493916*
X460520Y493874*
G54D134*
G55*
X43100Y103500D03*
X46863Y378983*
X65763Y370883*
X59384Y637701*
X84296Y192448*
X149031Y168900*
X115096Y186970*
X79922Y632686*
X80191Y647887*
X80653Y747704*
X80464Y764806*
X217113Y130860*
X172685Y172033*
X168353Y140290*
X189415Y413533*
X185266Y481943*
X225231Y61620*
X225002Y130816*
X231350Y214208*
X226428Y395041*
X222254Y394949*
X236637Y383693*
X241728Y364256*
X237455Y375355*
X246800Y436600*
X231108Y464137*
X226992Y464083*
X537200Y394400*
X657609Y470923*
X661709Y466823*
X674109Y454523*
X678509Y450323*
X654800Y529500*
X736209Y475223*
X740309Y479423*
X723809Y462723*
X719709Y458623*
G54D132*
G55*
X77200Y199800D03*
X24390Y497166*
X95441Y203600*
X215461Y461171*
X215434Y464704*
X229600Y454700*
X294900Y466600*
X475128Y493916*
X456920Y493874*
G54D89*
G55*
X59800Y764900D03*
X93130Y145135*
X212000Y171900*
X201547Y407074*
X207141Y386759*
X185614Y458881*
X215006Y438401*
X190714Y458681*
X247262Y519409*
G54D134*
G55*
X43100Y106900D03*
X46863Y382383*
X65763Y374283*
X59384Y641101*
X84296Y195848*
X149031Y172300*
X115096Y190370*
X79922Y636086*
X80191Y651287*
X80653Y751104*
X80464Y768206*
X217113Y134260*
X172685Y175433*
X168353Y143690*
X185266Y485343*
X189415Y416933*
X225231Y65020*
X225002Y134216*
X231350Y217608*
X226428Y398441*
X222254Y398349*
X236637Y387093*
X241728Y367656*
X237455Y378755*
X246800Y440000*
X231108Y467537*
X226992Y467483*
X537200Y397800*
X657609Y474323*
X661709Y470223*
X674109Y457923*
X678509Y453723*
X654800Y532900*
X736209Y478623*
X740309Y482823*
X723809Y466123*
X719709Y462023*
G54D131*
G55*
X77453Y525824D03*
X69970Y521539*
X66497Y521555*
X59007Y525728*
X55470Y525648*
X47790Y521300*
X44031Y521396*
X136663Y521903*
X133163Y522003*
X147678Y526068*
X144206Y526034*
X125501Y526046*
X122044Y526062*
X114546Y521952*
X110786Y521951*
X103330Y525965*
X99797Y525846*
X92158Y521634*
X88606Y521633*
X81117Y525760*
X204811Y77927*
X153061Y168712*
X219655Y214498*
X200498Y388564*
X205667Y406683*
X214163Y526003*
X210563Y526103*
X202963Y521903*
X199363*
X191863Y526203*
X188363*
X180845Y521911*
X177324Y521927*
X169812Y526147*
X166180Y526146*
X158691Y521893*
X155181Y521942*
X258530Y81926*
X243200Y520700*
X277254Y845565*
X337612Y430423*
X341344*
X360415*
X356714*
X352814*
X348914*
X345014*
X387100*
X383102*
X371187*
X367432*
X363968*
X379184*
X375464*
G54D89*
G55*
X59800Y770500D03*
X93130Y150735*
X212000Y177500*
X201547Y412674*
X207141Y392359*
X185614Y464481*
X215006Y444001*
X190714Y464281*
X247262Y525009*
G54D98*
G55*
X43760Y172352D03*
X69800Y180800*
X103041Y203500*
X115041Y202800*
X144600Y233900*
X214190Y98033*
X199561Y113456*
X189163Y240983*
X189121Y244556*
X189163Y248183*
Y237383*
X185309Y421839*
X189466Y493343*
X249782Y399333*
X249041Y383206*
X241555Y375055*
X241530Y371576*
X245865Y363969*
X245828Y360456*
X237500Y454700*
X223399Y778667*
X487203Y501502*
X487218Y494161*
X487223Y497927*
X515916Y424009*
X517452Y552477*
X517613Y548807*
X693339Y759399*
X693392Y762972*
X694427Y817304*
X694375Y820842*
G54D93*
G55*
X140847Y223231D03*
X162963*
G54D133*
G55*
X48500Y93600D03*
X66863Y267083*
X59263*
X66363Y272683*
X66863Y258783*
X59263Y258883*
X66863Y254683*
X59263Y251483*
X67063Y250483*
Y246283*
X59146Y242114*
X66963Y242083*
X67063Y237683*
X66863Y262883*
X66801Y294778*
Y290678*
X58863Y285083*
X66496Y285730*
Y281630*
X58863Y276783*
X66363*
X50680Y373862*
X66222Y517540*
X55179Y521570*
X43855Y517250*
X77242Y521666*
X91241Y203800*
X118571Y206661*
X143553Y331742*
X132417Y335856*
X120955Y331729*
X132863Y517903*
X88362Y517603*
X99385Y521826*
X110607Y517857*
X121751Y522079*
X143912Y522038*
X206425Y98053*
X154552Y335814*
X176638Y344153*
X165585Y339913*
X209880Y356594*
X198838Y352449*
X187757Y348289*
X192966Y481243*
X177049Y517848*
X154874Y517879*
X165905Y522020*
X210263Y522003*
X199063Y517803*
X188063Y522003*
X221359Y106010*
X250115Y93933*
X250090Y89833*
X248046Y77735*
X248190Y102533*
X248052Y73668*
X227102Y214585*
X252553Y387029*
X221085Y363914*
X246097Y432409*
X238700Y482954*
X234562Y779010*
X234666Y783159*
X234621Y787335*
X285742Y794780*
X338146Y793055*
X353927Y792923*
X308899Y794862*
X319115Y795010*
X297576Y794808*
X490830Y532955*
X490838Y541335*
X490523Y549911*
X478687Y490049*
X460541Y490002*
X490899Y508498*
X490902Y512828*
X450818Y508324*
X508100Y389700*
X511734Y424179*
X528810Y531644*
X528788Y527470*
X711409Y453923*
X661009Y474323*
X665109Y470223*
X677509Y457923*
X681909Y453723*
X692400Y537000*
X732109Y474523*
X727909Y470223*
X715509Y458023*
X729191Y857331*
G54D131*
G55*
X77453Y529424D03*
X69970Y525139*
X66497Y525155*
X59007Y529328*
X55470Y529248*
X47790Y524900*
X44031Y524996*
X136663Y525503*
X133163Y525603*
X147678Y529668*
X144206Y529634*
X125501Y529646*
X122044Y529662*
X114546Y525552*
X110786Y525551*
X103330Y529565*
X99797Y529446*
X92158Y525234*
X88606Y525233*
X81117Y529360*
X204811Y81527*
X153061Y172312*
X219655Y218098*
X200498Y392164*
X205667Y410283*
X214163Y529603*
X210563Y529703*
X202963Y525503*
X199363*
X191863Y529803*
X188363*
X180845Y525511*
X177324Y525527*
X169812Y529747*
X166180Y529746*
X158691Y525493*
X155181Y525542*
X258530Y85526*
X243200Y524300*
X277254Y849165*
X337612Y434023*
X341344*
X360415*
X356714*
X352814*
X348914*
X345014*
X387100*
X383102*
X371187*
X367432*
X363968*
X379184*
X375464*
G54D116*
G55*
X217108Y145568D03*
Y163568*
G54D99*
G55*
X147553Y327542D03*
X143853Y327642*
X136317Y331756*
X132717*
X124973Y327655*
X121255Y327729*
X201315Y81433*
X154641Y154448*
X191557Y344189*
X188047Y344249*
X180438Y340053*
X176898Y340013*
X169385Y335813*
X165885*
X158445Y331748*
X154845Y331848*
X185315Y410533*
X213780Y352494*
X210180*
X202638Y348349*
X199138*
X206788Y420845*
X207834Y465396*
X221100Y134300*
X249515Y394680*
X224885Y359814*
X221424Y359867*
X256700Y489500*
X260200*
X353898Y467743*
X349945Y467753*
X358012Y467743*
X345813*
X394125Y398023*
X390405*
X383048*
X379164*
X397699*
X386726*
X375610*
X365427Y467743*
X361642*
X451123Y503983*
X504316Y397727*
X664700Y543300*
G54D98*
G55*
X47360Y172352D03*
X73400Y180800*
X106641Y203500*
X118641Y202800*
X148200Y233900*
X217790Y98033*
X203161Y113456*
X192763Y240983*
X192721Y244556*
X192763Y248183*
Y237383*
X188909Y421839*
X193066Y493343*
X253382Y399333*
X252641Y383206*
X245155Y375055*
X245130Y371576*
X249465Y363969*
X249428Y360456*
X241100Y454700*
X226999Y778667*
X490803Y501502*
X490818Y494161*
X490823Y497927*
X519516Y424009*
X521052Y552477*
X521213Y548807*
X696939Y759399*
X696992Y762972*
X698027Y817304*
X697975Y820842*
G54D92*
G55*
X151400Y54700D03*
X116689Y54714*
X103528*
X151400Y66300*
X116689Y66314*
X103528*
X164500Y54700*
Y66300*
G54D133*
G55*
X45100Y93600D03*
X63463Y267083*
X55863*
X62963Y272683*
X63463Y258783*
X55863Y258883*
X63463Y254683*
X55863Y251483*
X63663Y250483*
Y246283*
X55746Y242114*
X63563Y242083*
X63663Y237683*
X63463Y262883*
X63401Y294778*
Y290678*
X55463Y285083*
X63096Y285730*
Y281630*
X55463Y276783*
X62963*
X47280Y373862*
X62822Y517540*
X51779Y521570*
X40455Y517250*
X73842Y521666*
X87841Y203800*
X115171Y206661*
X140153Y331742*
X129017Y335856*
X117555Y331729*
X129463Y517903*
X84962Y517603*
X95985Y521826*
X107207Y517857*
X118351Y522079*
X140512Y522038*
X217959Y106010*
X203025Y98053*
X151152Y335814*
X173238Y344153*
X162185Y339913*
X206480Y356594*
X217685Y363914*
X195438Y352449*
X184357Y348289*
X189566Y481243*
X173649Y517848*
X151474Y517879*
X162505Y522020*
X206863Y522003*
X195663Y517803*
X184663Y522003*
X246715Y93933*
X246690Y89833*
X244646Y77735*
X244790Y102533*
X244652Y73668*
X223702Y214585*
X249153Y387029*
X242697Y432409*
X235300Y482954*
X231162Y779010*
X231266Y783159*
X231221Y787335*
X282342Y794780*
X334746Y793055*
X350527Y792923*
X305499Y794862*
X315715Y795010*
X294176Y794808*
X487430Y532955*
X487438Y541335*
X487123Y549911*
X475287Y490049*
X457141Y490002*
X487499Y508498*
X487502Y512828*
X447418Y508324*
X504700Y389700*
X508334Y424179*
X525410Y531644*
X525388Y527470*
X708009Y453923*
X657609Y474323*
X712109Y458023*
X661709Y470223*
X674109Y457923*
X678509Y453723*
X689000Y537000*
X728709Y474523*
X724509Y470223*
X725791Y857331*
G54D90*
G55*
X77688Y184954D03*
X24894Y493063*
X149631Y176850*
X157313Y171759*
X208182Y427789*
X211343Y418666*
X244700Y461100*
X235756Y478217*
X236673Y468923*
X299174Y475788*
X294700Y462500*
X299213Y471007*
G54D127*
G55*
X134000Y52600D03*
Y77400*
X281963Y485753*
Y510553*
X340774Y65179*
Y40379*
X310274Y65179*
Y40379*
X343791Y395598*
X343292Y485604*
X312767Y485379*
X343791Y420398*
X323221Y445562*
Y470362*
X343292Y510404*
X312767Y510179*
X371274Y65179*
Y40379*
G54D40*
G55*
X33845Y507529D03*
Y499929*
X41797Y500609*
Y508209*
X99375Y144069*
Y151669*
X123397Y144069*
Y151669*
X115601Y144069*
Y151669*
X107672Y144069*
Y151669*
X174950Y133259*
X183700Y133300*
X183034Y162805*
Y170405*
X197209Y165797*
Y158197*
X174950Y140859*
X183700Y140900*
X205600Y165800*
Y158200*
X194877Y385099*
Y392699*
X187165Y385235*
Y392835*
X195311Y407990*
Y415590*
X215284Y382027*
Y389627*
X200959Y429749*
Y422149*
X197214Y464181*
Y456581*
X238000Y60400*
Y52800*
X263100Y60400*
Y52800*
X254900Y60400*
Y52800*
X246400Y60400*
Y52800*
X223321Y389661*
Y382061*
X254182Y496347*
Y503947*
X237203Y519878*
Y527478*
X261424Y519113*
Y526713*
X253508Y519183*
Y526783*
X238118Y504116*
Y496516*
X246132Y504110*
Y496510*
X262501Y504118*
Y496518*
X229241Y527601*
Y520001*
G54D118*
G55*
X200788Y473418D03*
X216324*
X200788Y493918*
X216324*
G54D143*
G55*
X147553Y323942D03*
X143853Y324042*
X136317Y328156*
X132717*
X124973Y324055*
X121255Y324129*
X201315Y77833*
X154641Y150848*
X202638Y344749*
X199138*
X191557Y340589*
X188047Y340649*
X180438Y336453*
X176898Y336413*
X169385Y332213*
X165885*
X158445Y328148*
X154845Y328248*
X185315Y406933*
X213780Y348894*
X210180*
X206788Y417245*
X207834Y461796*
X221100Y130700*
X249515Y391080*
X224885Y356214*
X221424Y356267*
X256700Y485900*
X260200*
X353898Y464143*
X349945Y464153*
X358012Y464143*
X345813*
X394125Y394423*
X390405*
X383048*
X379164*
X397699*
X386726*
X375610*
X365427Y464143*
X361642*
X451123Y500383*
X504316Y394127*
X664700Y539700*
G54D91*
G55*
X501750Y380000D03*
X520250*
G54D126*
G55*
X216324Y483668D03*
X200788*
G54D122*
G55*
X97645Y134201D03*
X92645*
X87645*
X82645*
Y114201*
X87645*
X92645*
X97645*
G54D47*
G55*
X73943Y205660D03*
Y213410*
X72930Y633923*
Y641673*
X65430Y637798*
X72814Y652628*
Y660378*
X65314Y656503*
X73412Y748676*
Y756426*
X65912Y752551*
X73356Y767193*
Y774943*
X65856Y771068*
X81443Y209535*
G54D113*
G55*
X216447Y72290D03*
Y74259*
Y76227*
Y78196*
Y80164*
Y82133*
Y84102*
Y86070*
Y88039*
Y90007*
Y91976*
X235733*
Y90007*
Y88039*
Y86070*
Y84102*
Y82133*
Y80164*
Y78196*
Y76227*
Y74259*
Y72290*
G54D112*
G55*
X497166Y535119D03*
Y537679*
Y540239*
Y542799*
X519366*
Y540239*
Y537679*
Y535119*
X695412Y836919*
Y834419*
Y831919*
Y829419*
Y826919*
X696098Y796516*
Y794016*
Y791516*
Y789016*
Y786516*
Y784016*
Y781516*
Y779016*
Y776516*
Y774016*
Y771516*
Y769016*
X695412Y854419*
Y851919*
Y849419*
Y846919*
Y844419*
Y841919*
Y839419*
X716012Y826919*
Y829419*
Y831919*
Y834419*
Y836919*
X716698Y769016*
Y771516*
Y774016*
Y776516*
Y779016*
Y781516*
Y784016*
Y786516*
Y789016*
Y791516*
Y794016*
Y796516*
X716012Y839419*
Y841919*
Y844419*
Y846919*
Y849419*
Y851919*
Y854419*
G54D97*
G55*
X45100Y89400D03*
X45200Y82900*
X72569Y219284*
X70277Y517540*
X59282Y521602*
X48002Y517237*
X63807Y647187*
X64298Y761923*
X149282Y164664*
X110971Y182699*
X84700Y141100*
X115141Y199000*
X117341Y194500*
X147610Y331731*
X136517Y335856*
X125273Y331655*
X136963Y517903*
X81425Y521698*
X92450Y517603*
X103504Y521857*
X114725Y517858*
X125800Y522071*
X147954Y522037*
X214222Y101900*
X203020Y93789*
X201664Y85481*
X203290Y102533*
X160361Y145062*
X159849Y176397*
X176482Y271928*
X176343Y267018*
X177356Y261409*
X175709Y256562*
X175577Y251228*
X175450Y246422*
X173990Y237502*
Y241702*
X176410Y281361*
X176443Y276656*
X176610Y294061*
X176510Y285561*
X176610Y289861*
X158681Y335850*
X180738Y344153*
X169685Y339913*
X214080Y356594*
X202938Y352449*
X191857Y348289*
X212100Y449700*
X189566Y485443*
Y489543*
X181104Y517848*
X158967Y517830*
X170087Y522020*
X214463Y521903*
X203263Y517803*
X192163Y522003*
X244790Y98033*
X223666Y218917*
X232758Y405205*
X249809Y403106*
X225139Y363907*
X242703Y428291*
X235199Y461252*
X235316Y473688*
X358000Y792962*
X342834Y792836*
X458763Y514834*
X466395*
X487437Y528628*
X487483Y537159*
X487213Y545645*
X487366Y489976*
X529300Y393000*
X645700Y394600*
X670009Y462023*
X653509Y478423*
X649409Y482723*
X665909Y466123*
X688300Y544300*
X732809Y478623*
X736909Y482823*
X720409Y466123*
X716309Y462023*
X747300Y546500*
X749500Y555900*
Y551800*
X749600Y577500*
X749530Y569233*
X749537Y560714*
X749629Y573387*
X725800Y853200*
G54D90*
G55*
X30494Y493063D03*
X83288Y184954*
X162913Y171759*
X155231Y176850*
X213782Y427789*
X216943Y418666*
X250300Y461100*
X241356Y478217*
X242273Y468923*
X304774Y475788*
X300300Y462500*
X304813Y471007*
G54D125*
G55*
X71660Y193550D03*
X69100*
X66540*
Y187050*
X71660*
G54D124*
G55*
X193000Y130850D03*
Y146350*
X274405Y63139*
Y47639*
G54D123*
G55*
X194548Y827952D03*
Y837401*
Y846849*
G54D119*
G55*
X510634Y403425D03*
Y408425*
Y413425*
X530634*
Y408425*
Y403425*
X510634Y418425*
X530634*
G54D115*
G55*
X151866Y100449D03*
X189416*
G54D110*
G55*
X75118Y561024D03*
Y564174*
Y567323*
Y570473*
Y573622*
Y576772*
Y579922*
Y583071*
Y586221*
Y589370*
Y592520*
Y595670*
Y598819*
Y601969*
Y605118*
Y608268*
Y611418*
Y614567*
Y679134*
Y682284*
Y685433*
Y688583*
Y691732*
Y694882*
Y698032*
Y701181*
Y704331*
Y707480*
Y710630*
Y713780*
Y716929*
Y720079*
Y723228*
Y726378*
Y729528*
Y732677*
X85000Y562599*
Y565748*
Y568898*
Y572048*
Y575197*
Y578347*
Y581496*
Y584646*
Y587796*
Y590945*
Y594095*
Y597244*
Y600394*
Y603544*
Y606693*
Y609843*
Y612992*
Y616142*
Y680709*
Y683858*
Y687008*
Y690158*
Y693307*
Y696457*
Y699606*
Y702756*
Y705906*
Y709055*
Y712205*
Y715354*
Y718504*
Y721654*
Y724803*
Y727953*
Y731102*
Y734252*
X175118Y818504*
Y821654*
Y824804*
Y827954*
Y831104*
Y834254*
Y837399*
X165238Y816929*
Y820079*
Y823229*
Y826379*
Y829529*
Y832679*
Y835829*
X175118Y840549*
X165238Y838974*
Y842124*
X175118Y843699*
Y846849*
Y849999*
Y853149*
Y856299*
X165238Y845274*
Y848424*
Y851574*
Y854724*
G54D97*
G55*
X48500Y89400D03*
X48600Y82900*
X75969Y219284*
X73677Y517540*
X62682Y521602*
X51402Y517237*
X67207Y647187*
X67698Y761923*
X114371Y182699*
X88100Y141100*
X118541Y199000*
X120741Y194500*
X139917Y335856*
X128673Y331655*
X140363Y517903*
X84825Y521698*
X95850Y517603*
X106904Y521857*
X118125Y517858*
X129200Y522071*
X217622Y101900*
X206420Y93789*
X205064Y85481*
X206690Y102533*
X152682Y164664*
X163761Y145062*
X163249Y176397*
X179882Y271928*
X179743Y267018*
X180756Y261409*
X179109Y256562*
X178977Y251228*
X178850Y246422*
X177390Y237502*
Y241702*
X179810Y281361*
X179843Y276656*
X180010Y294061*
X179910Y285561*
X180010Y289861*
X162081Y335850*
X151010Y331731*
X184138Y344153*
X173085Y339913*
X217480Y356594*
X206338Y352449*
X195257Y348289*
X215500Y449700*
X192966Y485443*
Y489543*
X184504Y517848*
X151354Y522037*
X162367Y517830*
X173487Y522020*
X217863Y521903*
X206663Y517803*
X195563Y522003*
X248190Y98033*
X227066Y218917*
X236158Y405205*
X253209Y403106*
X228539Y363907*
X246103Y428291*
X238599Y461252*
X238716Y473688*
X346234Y792836*
X361400Y792962*
X462163Y514834*
X469795*
X490837Y528628*
X490883Y537159*
X490613Y545645*
X490766Y489976*
X532700Y393000*
X649100Y394600*
X673409Y462023*
X656909Y478423*
X652809Y482723*
X669309Y466123*
X691700Y544300*
X736209Y478623*
X740309Y482823*
X723809Y466123*
X719709Y462023*
X750700Y546500*
X752900Y555900*
Y551800*
X753000Y577500*
X752930Y569233*
X752937Y560714*
X753029Y573387*
X729200Y853200*
G54D111*
G55*
X513500Y396160D03*
Y393600*
Y391040*
X520900*
Y393600*
Y396160*
G54D146*
G55*
X166649Y132647D03*
G54D144*
G55*
X226090Y82133D03*
G54D100*
G55*
X68140Y665912D03*
X104541Y207700*
X250667Y69296*
X277770Y794774*
X532500Y397400*
G54D96*
G55*
X63000Y103300D03*
X67300*
X50963Y382383*
X46763Y397883*
X50830Y397889*
X50963Y390183*
X46763Y390483*
X61563Y374283*
X60122Y754461*
X107783Y86561*
X91178Y211333*
X80326Y658988*
X79967Y643494*
X80653Y758647*
X80415Y776333*
X208612Y81430*
X219504Y181570*
X177087Y175433*
X185215Y418033*
X185266Y493043*
X219303Y748114*
X229613Y64898*
X223817Y181608*
X235414Y217713*
X240662Y387084*
X241728Y360156*
X237455Y371255*
X238000Y418100*
X227900Y418000*
X242700Y440000*
X232100Y418000*
X223658Y748114*
X234524Y774783*
X447090Y503842*
X504027Y412875*
X504094Y405332*
X503981Y420419*
X525463Y545933*
X665909Y466123*
X649409Y482723*
X670009Y462023*
X653509Y478423*
X711409Y453923*
X650700Y532900*
X689190Y771506*
X715509Y457923*
X732109Y474523*
X727909Y470223*
G54D95*
G55*
X139878Y135201D03*
Y150469*
G54D66*
G55*
X72838Y388509D03*
X68901*
X72838Y392446*
X68901*
X64964*
X72838Y396383*
X68901*
X64964*
X68901Y486935*
Y494809*
X72838*
X64964Y490872*
X68901*
X72838*
X64964Y486935*
X72838*
X167327Y388509*
X163390*
X171264Y392446*
X167327*
X163390*
X171264Y396383*
X167327*
X163390*
X171264Y486935*
X167327*
X163390*
X171264Y490872*
X167327*
X163390*
X167327Y494809*
X163390*
G54D57*
G55*
X672257Y523769D03*
G54D130*
G55*
X129310Y186223D03*
Y204175*
G54D61*
G55*
X164396Y151107D03*
Y165087*
X170302*
Y151107*
G54D147*
G55*
X246455Y107057D03*
G54D145*
G55*
X62540Y665912D03*
X98941Y207700*
X245067Y69296*
X272170Y794774*
X526900Y397400*
G54D94*
G55*
X64964Y416068D03*
X68901*
X72838*
X76775*
X64964Y412131*
X68901*
X72838*
X76775*
X64964Y408194*
X68901*
X72838*
X76775*
X64964Y404257*
X68901*
X72838*
X76775*
X64964Y400320*
X68901*
X72838*
X76775*
Y396383*
Y392446*
Y388509*
X64964Y482998*
X68901*
X72838*
X76775*
X64964Y479061*
X68901*
X72838*
X76775*
X64964Y475124*
X68901*
X72838*
X76775*
X64964Y471187*
X68901*
X72838*
X76775*
X64964Y467250*
X68901*
X72838*
X76775*
X64964Y463313*
X68901*
X72838*
X76775*
X64964Y459376*
X68901*
X72838*
X76775*
X64964Y455439*
X68901*
X72838*
X76775*
X64964Y451502*
X68901*
X72838*
X76775*
X64964Y447565*
X68901*
X72838*
X76775*
X64964Y443628*
X68901*
X72838*
X76775*
X64964Y439690*
X68901*
X72838*
X76775*
X64964Y435753*
X68901*
X72838*
X76775*
X64964Y431816*
X68901*
X72838*
X76775*
X64964Y427879*
X68901*
X72838*
X76775*
X64964Y423942*
X68901*
X72838*
X76775*
X64964Y420005*
X68901*
X72838*
X76775*
Y494809*
Y490872*
Y486935*
X80712Y416068*
X84649*
X88586*
X92523*
X96460*
X100397*
X104334*
X108271*
X112208*
X116145*
X120083*
X124020*
X127957*
X131894*
X135831*
X139768*
X143705*
X147642*
X80712Y412131*
X84649*
X88586*
X92523*
X96460*
X100397*
X104334*
X108271*
X112208*
X116145*
X120083*
X124020*
X127957*
X131894*
X135831*
X139768*
X143705*
X147642*
X80712Y408194*
X84649*
X88586*
X92523*
X96460*
X100397*
X104334*
X108271*
X112208*
X116145*
X120083*
X124020*
X127957*
X131894*
X135831*
X139768*
X143705*
X147642*
X80712Y404257*
X84649*
X88586*
X92523*
X96460*
X100397*
X104334*
X108271*
X112208*
X116145*
X120083*
X124020*
X127957*
X131894*
X135831*
X139768*
X143705*
X147642*
X80712Y400320*
X84649*
X88586*
X92523*
X96460*
X100397*
X104334*
X108271*
X112208*
X116145*
X120083*
X124020*
X127957*
X131894*
X135831*
X139768*
X143705*
X147642*
X80712Y396383*
X84649*
X88586*
X92523*
X96460*
X100397*
X104334*
X108271*
X112208*
X116145*
X120083*
X124020*
X127957*
X131894*
X135831*
X139768*
X143705*
X147642*
X80712Y392446*
X84649*
X88586*
X92523*
X96460*
X100397*
X104334*
X108271*
X112208*
X116145*
X120083*
X124020*
X127957*
X131894*
X135831*
X139768*
X143705*
X147642*
X80712Y388509*
X84649*
X88586*
X92523*
X96460*
X100397*
X104334*
X108271*
X112208*
X116145*
X120083*
X124020*
X127957*
X131894*
X135831*
X139768*
X143705*
X147642*
X80712Y482998*
X84649*
X88586*
X92523*
X96460*
X100397*
X104334*
X108271*
X112208*
X116145*
X120083*
X124020*
X127957*
X131894*
X135831*
X139768*
X143705*
X147642*
X80712Y479061*
X84649*
X88586*
X92523*
X96460*
X100397*
X104334*
X108271*
X112208*
X116145*
X120083*
X124020*
X127957*
X131894*
X135831*
X139768*
X143705*
X147642*
X80712Y475124*
X84649*
X88586*
X92523*
X96460*
X100397*
X104334*
X108271*
X112208*
X116145*
X120083*
X124020*
X127957*
X131894*
X135831*
X139768*
X143705*
X147642*
X80712Y471187*
X84649*
X88586*
X92523*
X96460*
X100397*
X104334*
X108271*
X112208*
X116145*
X120083*
X124020*
X127957*
X131894*
X135831*
X139768*
X143705*
X147642*
X80712Y467250*
X84649*
X88586*
X92523*
X96460*
X100397*
X104334*
X108271*
X112208*
X116145*
X120083*
X124020*
X127957*
X131894*
X135831*
X139768*
X143705*
X147642*
X80712Y463313*
X84649*
X88586*
X92523*
X96460*
X100397*
X104334*
X108271*
X112208*
X116145*
X120083*
X124020*
X127957*
X131894*
X135831*
X139768*
X143705*
X147642*
X80712Y459376*
X84649*
X88586*
X92523*
X96460*
X100397*
X104334*
X108271*
X112208*
X116145*
X120083*
X124020*
X127957*
X131894*
X135831*
X139768*
X143705*
X147642*
X80712Y455439*
X84649*
X88586*
X92523*
X96460*
X100397*
X104334*
X108271*
X112208*
X116145*
X120083*
X124020*
X127957*
X131894*
X135831*
X139768*
X143705*
X147642*
X80712Y451502*
X84649*
X88586*
X92523*
X96460*
X100397*
X104334*
X108271*
X112208*
X116145*
X120083*
X124020*
X127957*
X131894*
X135831*
X139768*
X143705*
X147642*
X80712Y447565*
X84649*
X88586*
X92523*
X96460*
X100397*
X104334*
X108271*
X112208*
X116145*
X120083*
X124020*
X127957*
X131894*
X135831*
X139768*
X143705*
X147642*
X80712Y443628*
X84649*
X88586*
X92523*
X96460*
X100397*
X104334*
X108271*
X112208*
X116145*
X120083*
X124020*
X127957*
X131894*
X135831*
X139768*
X143705*
X147642*
X80712Y439690*
X84649*
X88586*
X92523*
X96460*
X100397*
X104334*
X108271*
X112208*
X116145*
X120083*
X124020*
X127957*
X131894*
X135831*
X139768*
X143705*
X147642*
X80712Y435753*
X84649*
X88586*
X92523*
X96460*
X100397*
X104334*
X108271*
X112208*
X116145*
X120083*
X124020*
X127957*
X131894*
X135831*
X139768*
X143705*
X147642*
X80712Y431816*
X84649*
X88586*
X92523*
X96460*
X100397*
X104334*
X108271*
X112208*
X116145*
X120083*
X124020*
X127957*
X131894*
X135831*
X139768*
X143705*
X147642*
X80712Y427879*
X84649*
X88586*
X92523*
X96460*
X100397*
X104334*
X108271*
X112208*
X116145*
X120083*
X124020*
X127957*
X131894*
X135831*
X139768*
X143705*
X147642*
X80712Y423942*
X84649*
X88586*
X92523*
X96460*
X100397*
X104334*
X108271*
X112208*
X116145*
X120083*
X124020*
X127957*
X131894*
X135831*
X139768*
X143705*
X147642*
X80712Y420005*
X84649*
X88586*
X92523*
X96460*
X100397*
X104334*
X108271*
X112208*
X116145*
X120083*
X124020*
X127957*
X131894*
X135831*
X139768*
X143705*
X147642*
X80712Y494809*
X84649*
X88586*
X92523*
X96460*
X100397*
X104334*
X108271*
X112208*
X116145*
X120083*
X124020*
X127957*
X131894*
X135831*
X139768*
X143705*
X147642*
X80712Y490872*
X84649*
X88586*
X92523*
X96460*
X100397*
X104334*
X108271*
X112208*
X116145*
X120083*
X124020*
X127957*
X131894*
X135831*
X139768*
X143705*
X147642*
X80712Y486935*
X84649*
X88586*
X92523*
X96460*
X100397*
X104334*
X108271*
X112208*
X116145*
X120083*
X124020*
X127957*
X131894*
X135831*
X139768*
X143705*
X147642*
X163390Y416068*
X167327*
X171264*
X163390Y412131*
X167327*
X171264*
X163390Y408194*
X167327*
X171264*
X163390Y404257*
X167327*
X171264*
X163390Y400320*
X167327*
X171264*
X151579Y416068*
X155516*
X159453*
X151579Y412131*
X155516*
X159453*
X151579Y408194*
X155516*
X159453*
X151579Y404257*
X155516*
X159453*
X151579Y400320*
X155516*
X159453*
X151579Y396383*
X155516*
X159453*
X151579Y392446*
X155516*
X159453*
X151579Y388509*
X155516*
X159453*
X163390Y482998*
X167327*
X171264*
X163390Y479061*
X167327*
X171264*
X163390Y475124*
X167327*
X171264*
X163390Y471187*
X167327*
X171264*
X163390Y467250*
X167327*
X171264*
X163390Y463313*
X167327*
X171264*
X163390Y459376*
X167327*
X171264*
X163390Y455439*
X167327*
X171264*
X163390Y451502*
X167327*
X171264*
X163390Y447565*
X167327*
X171264*
X163390Y443628*
X167327*
X171264*
X163390Y439690*
X167327*
X171264*
X163390Y435753*
X167327*
X171264*
X163390Y431816*
X167327*
X171264*
X163390Y427879*
X167327*
X171264*
X163390Y423942*
X167327*
X171264*
X163390Y420005*
X167327*
X171264*
X151579Y482998*
X155516*
X159453*
X151579Y479061*
X155516*
X159453*
X151579Y475124*
X155516*
X159453*
X151579Y471187*
X155516*
X159453*
X151579Y467250*
X155516*
X159453*
X151579Y463313*
X155516*
X159453*
X151579Y459376*
X155516*
X159453*
X151579Y455439*
X155516*
X159453*
X151579Y451502*
X155516*
X159453*
X151579Y447565*
X155516*
X159453*
X151579Y443628*
X155516*
X159453*
X151579Y439690*
X155516*
X159453*
X151579Y435753*
X155516*
X159453*
X151579Y431816*
X155516*
X159453*
X151579Y427879*
X155516*
X159453*
X151579Y423942*
X155516*
X159453*
X151579Y420005*
X155516*
X159453*
X151579Y494809*
X155516*
X159453*
X151579Y490872*
X155516*
X159453*
X151579Y486935*
X155516*
X159453*
G54D27*
G55*
X52900Y645300D03*
Y634300*
Y748300*
Y759300*
X205600Y135800*
Y146800*
X294751Y448610*
Y437610*
X303549Y448556*
Y437556*
G54D62*
G55*
X160359Y154160D03*
Y156128*
Y158097*
Y160066*
Y162034*
X174339*
Y160066*
Y158097*
Y156128*
Y154160*
G54D59*
G55*
X662514Y518651D03*
Y521210*
Y523769*
Y526328*
Y528887*
X682000*
Y526328*
Y523769*
Y521210*
Y518651*
G54D102*
G55*
X104382Y212614D03*
X99525Y212610*
X212700Y129700*
X168084Y172055*
X212492Y403033*
X217363Y401778*
X185934Y470229*
X203439Y459352*
X194624Y421463*
X190765Y470328*
X264353Y484934*
X222577Y522519*
X341430Y463151*
X371408Y393555*
X366586*
X361719*
G54D141*
G55*
X246455Y109757D03*
G54D148*
G55*
X167349Y158097D03*
G54D114*
G55*
X220569Y204940D03*
X223129*
X225689*
X228249*
Y188760*
X225689*
X223129*
X220569*
X237750Y428000*
X235250*
X232750*
X230250*
X227750*
X225250*
X222750*
X220250*
Y448600*
X222750*
X225250*
X227750*
X230250*
X232750*
X235250*
X237750*
X228249Y755690*
X225689*
X223129*
X220569*
Y771870*
X223129*
X225689*
X228249*
G54D58*
G55*
X667139Y533512D03*
X669698*
X672257*
X674816*
X677375*
Y514026*
X674816*
X672257*
X669698*
X667139*
G54D102*
G55*
X104382Y218214D03*
X99525Y218210*
X212700Y135300*
X168084Y177655*
X212492Y408633*
X217363Y407378*
X185934Y475829*
X203439Y464952*
X194624Y427063*
X190765Y475928*
X222577Y528119*
X264353Y490534*
X341430Y468751*
X371408Y399155*
X366586*
X361719*
G54D117*
G55*
X702989Y515755D03*
X691989*
X703000Y524500*
X692000*
G54D108*
G55*
X234222Y399876D03*
Y396136*
Y392396*
X243222*
Y399876*
G54D142*
G55*
X166649Y135347D03*
G54D120*
G55*
X268768Y415628D03*
Y430628*
G54D214*
G55*
X-299221Y825297D03*
X-303521*
X-287184Y546214*
X-282984Y530714*
X-287051Y530708*
X-287184Y538414*
X-282984Y538114*
X-297784Y554314*
X-296343Y174136*
X-344004Y842036*
X-327399Y717264*
X-316547Y269609*
X-316188Y285103*
X-316874Y169950*
X-316636Y152264*
X-444833Y847167*
X-455725Y747027*
X-413308Y753164*
X-421436Y510564*
X-421487Y435554*
X-455524Y180483*
X-465834Y863699*
X-460038Y746989*
X-471635Y710884*
X-474221Y510497*
X-464121Y510597*
X-468321*
X-476883Y541513*
X-477949Y568441*
X-473676Y557342*
X-478921Y488597*
X-459879Y180483*
X-470745Y153814*
X-683311Y424755*
X-740248Y515722*
X-740315Y523265*
X-740202Y508178*
X-761684Y382664*
X-902130Y462474*
X-885630Y445874*
X-906230Y466574*
X-889730Y450174*
X-947630Y474674*
X-886921Y395697*
X-925411Y157091*
X-951730Y470674*
X-968330Y454074*
X-964130Y458374*
G54D191*
G55*
X-279221Y570997D03*
X-481421Y374197*
G54D219*
G55*
X-306896Y790532D03*
X-291146*
X-306896Y769262*
X-291146*
G54D183*
G55*
X-269474Y438290D03*
X-261874*
X-269471Y446173*
X-261871*
X-482058Y841618*
X-489658*
X-538508Y468962*
X-530908*
X-890021Y404297*
X-882421*
X-890040Y412029*
X-882440*
G54D221*
G55*
X-294280Y840394D03*
Y838429*
Y836459*
Y834489*
Y832524*
X-310580*
Y834489*
Y836459*
Y838429*
Y840394*
X-344120Y728041*
Y730006*
Y731976*
Y733946*
Y735911*
X-327820*
Y733946*
Y731976*
Y730006*
Y728041*
X-318384Y680769*
Y678799*
Y676829*
Y674859*
Y672889*
Y670919*
Y668949*
Y666979*
Y665009*
Y663039*
Y661069*
Y659099*
Y657129*
Y655159*
Y653189*
Y651219*
Y649249*
Y647279*
Y645309*
Y643339*
Y641369*
Y639399*
Y637429*
Y635459*
X-393984Y651219*
Y653189*
Y655159*
Y657129*
Y659099*
Y661069*
Y663039*
Y665009*
Y666979*
Y668949*
Y670919*
Y672889*
Y674859*
Y676829*
Y678799*
Y680769*
Y635459*
Y637429*
Y639399*
Y641369*
Y643339*
Y645309*
Y647279*
Y649249*
X-712541Y417130*
Y419095*
Y421065*
Y423035*
Y425000*
X-696241*
Y423035*
Y421065*
Y419095*
Y417130*
G54D206*
G55*
X-264211Y428031D03*
X-317021Y725397*
X-335262Y721597*
X-455282Y464026*
X-455255Y460493*
X-469421Y470497*
X-534721Y458597*
X-714949Y431281*
X-696741Y431323*
G54D224*
G55*
X-279321Y821697D03*
X-283084Y546214*
X-301984Y554314*
X-295605Y287496*
X-320517Y732749*
X-385252Y756297*
X-351317Y738227*
X-316143Y292511*
X-316412Y277310*
X-316874Y177493*
X-316685Y160391*
X-453334Y794337*
X-408906Y753164*
X-404574Y784907*
X-425636Y511664*
X-421487Y443254*
X-461452Y863577*
X-461223Y794381*
X-467571Y710989*
X-462649Y530156*
X-458475Y530248*
X-472858Y541504*
X-477949Y560941*
X-473676Y549842*
X-483021Y488597*
X-467329Y461060*
X-463213Y461114*
X-773421Y530797*
X-893830Y454274*
X-897930Y458374*
X-910330Y470674*
X-914730Y474874*
X-891021Y395697*
X-972430Y449974*
X-976530Y445774*
X-960030Y462474*
X-955930Y466574*
G54D206*
G55*
X-313421Y725397D03*
X-260611Y428031*
X-331662Y721597*
X-451682Y464026*
X-451655Y460493*
X-465821Y470497*
X-531121Y458597*
X-711349Y431281*
X-693141Y431323*
G54D210*
G55*
X-296021Y160297D03*
X-329351Y780062*
X-448221Y753297*
X-437768Y518123*
X-443362Y538438*
X-421835Y466316*
X-451227Y486796*
X-426935Y466516*
X-483483Y405788*
G54D224*
G55*
X-279321Y818297D03*
X-283084Y542814*
X-301984Y550914*
X-295605Y284096*
X-320517Y729349*
X-385252Y752897*
X-351317Y734827*
X-316143Y289111*
X-316412Y273910*
X-316874Y174093*
X-316685Y156991*
X-453334Y790937*
X-408906Y749764*
X-404574Y781507*
X-421487Y439854*
X-425636Y508264*
X-461452Y860177*
X-461223Y790981*
X-467571Y707589*
X-462649Y526756*
X-458475Y526848*
X-472858Y538104*
X-477949Y557541*
X-473676Y546442*
X-483021Y485197*
X-467329Y457660*
X-463213Y457714*
X-773421Y527397*
X-893830Y450874*
X-897930Y454974*
X-910330Y467274*
X-914730Y471474*
X-891021Y392297*
X-972430Y446574*
X-976530Y442374*
X-960030Y459074*
X-955930Y463174*
G54D209*
G55*
X-313674Y399373D03*
X-306191Y403658*
X-302718Y403642*
X-295228Y399469*
X-291691Y399549*
X-284011Y403897*
X-280252Y403801*
X-372884Y403294*
X-369384Y403194*
X-383899Y399129*
X-380427Y399163*
X-361722Y399151*
X-358265Y399135*
X-350767Y403245*
X-347007Y403246*
X-339551Y399232*
X-336018Y399351*
X-328379Y403563*
X-324827Y403564*
X-317338Y399437*
X-441032Y847270*
X-389282Y756485*
X-455876Y710699*
X-436719Y536633*
X-441888Y518514*
X-450384Y399194*
X-446784Y399094*
X-439184Y403294*
X-435584*
X-428084Y398994*
X-424584*
X-417066Y403286*
X-413545Y403270*
X-406033Y399050*
X-402401Y399051*
X-394912Y403304*
X-391402Y403255*
X-494751Y843271*
X-479421Y404497*
X-513475Y79632*
X-573833Y494774*
X-577565*
X-596636*
X-592935*
X-589035*
X-585135*
X-581235*
X-623321*
X-619323*
X-607408*
X-603653*
X-600189*
X-615405*
X-611685*
G54D210*
G55*
X-296021Y154697D03*
X-329351Y774462*
X-448221Y747697*
X-437768Y512523*
X-443362Y532838*
X-421835Y460716*
X-451227Y481196*
X-426935Y460916*
X-483483Y400188*
G54D205*
G55*
X-279981Y752845D03*
X-306021Y744397*
X-339262Y721697*
X-351262Y722397*
X-380821Y691297*
X-450411Y827164*
X-435782Y811741*
X-425384Y684214*
X-425342Y680641*
X-425384Y677014*
Y687814*
X-421530Y503358*
X-425687Y431854*
X-486003Y525864*
X-485262Y541991*
X-477776Y550142*
X-477751Y553621*
X-482086Y561228*
X-482049Y564741*
X-473721Y470497*
X-459620Y146530*
X-723424Y423695*
X-723439Y431036*
X-723444Y427270*
X-752137Y501188*
X-753673Y372720*
X-753834Y376390*
X-929560Y165798*
X-929613Y162225*
X-930648Y107893*
X-930596Y104355*
G54D216*
G55*
X-377068Y701966D03*
X-399184*
G54D204*
G55*
X-284721Y831597D03*
X-303084Y658114*
X-295484*
X-302584Y652514*
X-303084Y666414*
X-295484Y666314*
X-303084Y670514*
X-295484Y673714*
X-303284Y674714*
Y678914*
X-295367Y683083*
X-303184Y683114*
X-303284Y687514*
X-303084Y662314*
X-303022Y630419*
Y634519*
X-295084Y640114*
X-302717Y639467*
Y643567*
X-295084Y648414*
X-302584*
X-286901Y551335*
X-302443Y407657*
X-291400Y403627*
X-280076Y407947*
X-313463Y403531*
X-327462Y721397*
X-354792Y718536*
X-379774Y593455*
X-368638Y589341*
X-357176Y593468*
X-369084Y407294*
X-324583Y407594*
X-335606Y403371*
X-346828Y407340*
X-357972Y403118*
X-380133Y403159*
X-442646Y827144*
X-390773Y589383*
X-412859Y581044*
X-401806Y585284*
X-446101Y568603*
X-435059Y572748*
X-423978Y576908*
X-429187Y443954*
X-413270Y407349*
X-391095Y407318*
X-402126Y403177*
X-446484Y403194*
X-435284Y407394*
X-424284Y403194*
X-457580Y819187*
X-486336Y831264*
X-486311Y835364*
X-484267Y847462*
X-484411Y822664*
X-484273Y851529*
X-463323Y710612*
X-488774Y538168*
X-457306Y561283*
X-482318Y492788*
X-474921Y442243*
X-470783Y146187*
X-470887Y142038*
X-470842Y137862*
X-521963Y130417*
X-574367Y132142*
X-590148Y132274*
X-545120Y130335*
X-555336Y130187*
X-533797Y130389*
X-727051Y392242*
X-727059Y383862*
X-726744Y375286*
X-714908Y435148*
X-696762Y435195*
X-727120Y416699*
X-727123Y412369*
X-687039Y416873*
X-744321Y535497*
X-747955Y501018*
X-765031Y393553*
X-765009Y397727*
X-947630Y471274*
X-897230Y450874*
X-901330Y454974*
X-913730Y467274*
X-918130Y471474*
X-928621Y388197*
X-968330Y450674*
X-964130Y454974*
X-951730Y467174*
X-965412Y67866*
G54D209*
G55*
X-313674Y395773D03*
X-306191Y400058*
X-302718Y400042*
X-295228Y395869*
X-291691Y395949*
X-284011Y400297*
X-280252Y400201*
X-372884Y399694*
X-369384Y399594*
X-383899Y395529*
X-380427Y395563*
X-361722Y395551*
X-358265Y395535*
X-350767Y399645*
X-347007Y399646*
X-339551Y395632*
X-336018Y395751*
X-328379Y399963*
X-324827Y399964*
X-317338Y395837*
X-441032Y843670*
X-389282Y752885*
X-455876Y707099*
X-436719Y533033*
X-441888Y514914*
X-450384Y395594*
X-446784Y395494*
X-439184Y399694*
X-435584*
X-428084Y395394*
X-424584*
X-417066Y399686*
X-413545Y399670*
X-406033Y395450*
X-402401Y395451*
X-394912Y399704*
X-391402Y399655*
X-494751Y839671*
X-479421Y400897*
X-513475Y76032*
X-573833Y491174*
X-577565*
X-596636*
X-592935*
X-589035*
X-585135*
X-581235*
X-623321*
X-619323*
X-607408*
X-603653*
X-600189*
X-615405*
X-611685*
G54D228*
G55*
X-453329Y779629D03*
Y761629*
G54D229*
G55*
X-383774Y597655D03*
X-380074Y597555*
X-372538Y593441*
X-368938*
X-361194Y597542*
X-357476Y597468*
X-437536Y843764*
X-390862Y770749*
X-427778Y581008*
X-424268Y580948*
X-416659Y585144*
X-413119Y585184*
X-405606Y589384*
X-402106*
X-394666Y593449*
X-391066Y593349*
X-421536Y514664*
X-450001Y572703*
X-446401*
X-438859Y576848*
X-435359*
X-443009Y504352*
X-444055Y459801*
X-457321Y790897*
X-485736Y530517*
X-461106Y565383*
X-457645Y565330*
X-492921Y435697*
X-496421*
X-590119Y457454*
X-586166Y457444*
X-594233Y457454*
X-582034*
X-630346Y527174*
X-626626*
X-619269*
X-615385*
X-633920*
X-622947*
X-611831*
X-601648Y457454*
X-597863*
X-687344Y421214*
X-740537Y527470*
X-900921Y381897*
G54D205*
G55*
X-283581Y752845D03*
X-309621Y744397*
X-342862Y721697*
X-354862Y722397*
X-384421Y691297*
X-454011Y827164*
X-439382Y811741*
X-428984Y684214*
X-428942Y680641*
X-428984Y677014*
Y687814*
X-425130Y503358*
X-429287Y431854*
X-489603Y525864*
X-488862Y541991*
X-481376Y550142*
X-481351Y553621*
X-485686Y561228*
X-485649Y564741*
X-477321Y470497*
X-463220Y146530*
X-727024Y423695*
X-727039Y431036*
X-727044Y427270*
X-755737Y501188*
X-757273Y372720*
X-757434Y376390*
X-933160Y165798*
X-933213Y162225*
X-934248Y107893*
X-934196Y104355*
G54D217*
G55*
X-387621Y870497D03*
X-352910Y870483*
X-339749*
X-387621Y858897*
X-352910Y858883*
X-339749*
X-400721Y870497*
Y858897*
G54D204*
G55*
X-281321Y831597D03*
X-299684Y658114*
X-292084*
X-299184Y652514*
X-299684Y666414*
X-292084Y666314*
X-299684Y670514*
X-292084Y673714*
X-299884Y674714*
Y678914*
X-291967Y683083*
X-299784Y683114*
X-299884Y687514*
X-299684Y662314*
X-299622Y630419*
Y634519*
X-291684Y640114*
X-299317Y639467*
Y643567*
X-291684Y648414*
X-299184*
X-283501Y551335*
X-299043Y407657*
X-288000Y403627*
X-276676Y407947*
X-310063Y403531*
X-324062Y721397*
X-351392Y718536*
X-376374Y593455*
X-365238Y589341*
X-353776Y593468*
X-365684Y407294*
X-321183Y407594*
X-332206Y403371*
X-343428Y407340*
X-354572Y403118*
X-376733Y403159*
X-454180Y819187*
X-439246Y827144*
X-387373Y589383*
X-409459Y581044*
X-398406Y585284*
X-442701Y568603*
X-453906Y561283*
X-431659Y572748*
X-420578Y576908*
X-425787Y443954*
X-409870Y407349*
X-387695Y407318*
X-398726Y403177*
X-443084Y403194*
X-431884Y407394*
X-420884Y403194*
X-482936Y831264*
X-482911Y835364*
X-480867Y847462*
X-481011Y822664*
X-480873Y851529*
X-459923Y710612*
X-485374Y538168*
X-478918Y492788*
X-471521Y442243*
X-467383Y146187*
X-467487Y142038*
X-467442Y137862*
X-518563Y130417*
X-570967Y132142*
X-586748Y132274*
X-541720Y130335*
X-551936Y130187*
X-530397Y130389*
X-723651Y392242*
X-723659Y383862*
X-723344Y375286*
X-711508Y435148*
X-693362Y435195*
X-723720Y416699*
X-723723Y412369*
X-683639Y416873*
X-740921Y535497*
X-744555Y501018*
X-761631Y393553*
X-761609Y397727*
X-944230Y471274*
X-893830Y450874*
X-948330Y467174*
X-897930Y454974*
X-910330Y467274*
X-914730Y471474*
X-925221Y388197*
X-964930Y450674*
X-960730Y454974*
X-962012Y67866*
G54D207*
G55*
X-313909Y740243D03*
X-261115Y432134*
X-385852Y748347*
X-393534Y753438*
X-444403Y497408*
X-447564Y506531*
X-480921Y464097*
X-471977Y446980*
X-472894Y456274*
X-535395Y449409*
X-530921Y462697*
X-535434Y454190*
G54D220*
G55*
X-370221Y872597D03*
Y847797*
X-518184Y439444*
Y414644*
X-576995Y860018*
Y884818*
X-546495Y860018*
Y884818*
X-580012Y529599*
X-579513Y439593*
X-548988Y439818*
X-580012Y504799*
X-559442Y479635*
Y454835*
X-579513Y414793*
X-548988Y415018*
X-607495Y860018*
Y884818*
G54D152*
G55*
X-270066Y417668D03*
Y425268*
X-278018Y424588*
Y416988*
X-335596Y781128*
Y773528*
X-359618Y781128*
Y773528*
X-351822Y781128*
Y773528*
X-343893Y781128*
Y773528*
X-411171Y791938*
X-419921Y791897*
X-419255Y762392*
Y754792*
X-433430Y759400*
Y767000*
X-411171Y784338*
X-419921Y784297*
X-441821Y759397*
Y766997*
X-431098Y540098*
Y532498*
X-423386Y539962*
Y532362*
X-431532Y517207*
Y509607*
X-451505Y543170*
Y535570*
X-437180Y495448*
Y503048*
X-433435Y461016*
Y468616*
X-474221Y864797*
Y872397*
X-499321Y864797*
Y872397*
X-491121Y864797*
Y872397*
X-482621Y864797*
Y872397*
X-459542Y535536*
Y543136*
X-490403Y428850*
Y421250*
X-473424Y405319*
Y397719*
X-497645Y406084*
Y398484*
X-489729Y406014*
Y398414*
X-474339Y421081*
Y428681*
X-482353Y421087*
Y428687*
X-498722Y421079*
Y428679*
X-465462Y397596*
Y405196*
G54D230*
G55*
X-437009Y451779D03*
X-452545*
X-437009Y431279*
X-452545*
G54D251*
G55*
X-383774Y601255D03*
X-380074Y601155*
X-372538Y597041*
X-368938*
X-361194Y601142*
X-357476Y601068*
X-437536Y847364*
X-390862Y774349*
X-438859Y580448*
X-435359*
X-427778Y584608*
X-424268Y584548*
X-416659Y588744*
X-413119Y588784*
X-405606Y592984*
X-402106*
X-394666Y597049*
X-391066Y596949*
X-421536Y518264*
X-450001Y576303*
X-446401*
X-443009Y507952*
X-444055Y463401*
X-457321Y794497*
X-485736Y534117*
X-461106Y568983*
X-457645Y568930*
X-492921Y439297*
X-496421*
X-590119Y461054*
X-586166Y461044*
X-594233Y461054*
X-582034*
X-630346Y530774*
X-626626*
X-619269*
X-615385*
X-633920*
X-622947*
X-611831*
X-601648Y461054*
X-597863*
X-687344Y424814*
X-740537Y531070*
X-900921Y385497*
G54D233*
G55*
X-737971Y545197D03*
X-756471*
G54D234*
G55*
X-452545Y441529D03*
X-437009*
G54D225*
G55*
X-333866Y790996D03*
X-328866*
X-323866*
X-318866*
Y810996*
X-323866*
X-328866*
X-333866*
G54D184*
G55*
X-310164Y719537D03*
Y711787*
X-309151Y291274*
Y283524*
X-301651Y287399*
X-309035Y272569*
Y264819*
X-301535Y268694*
X-309633Y176521*
Y168771*
X-302133Y172646*
X-309577Y158004*
Y150254*
X-302077Y154129*
X-317664Y715662*
G54D235*
G55*
X-452668Y852907D03*
Y850938*
Y848970*
Y847001*
Y845033*
Y843064*
Y841095*
Y839127*
Y837158*
Y835190*
Y833221*
X-471954*
Y835190*
Y837158*
Y839127*
Y841095*
Y843064*
Y845033*
Y847001*
Y848970*
Y850938*
Y852907*
G54D236*
G55*
X-733387Y390078D03*
Y387518*
Y384958*
Y382398*
X-755587*
Y384958*
Y387518*
Y390078*
X-931633Y88278*
Y90778*
Y93278*
Y95778*
Y98278*
X-932319Y128681*
Y131181*
Y133681*
Y136181*
Y138681*
Y141181*
Y143681*
Y146181*
Y148681*
Y151181*
Y153681*
Y156181*
X-931633Y70778*
Y73278*
Y75778*
Y78278*
Y80778*
Y83278*
Y85778*
X-952233Y98278*
Y95778*
Y93278*
Y90778*
Y88278*
X-952919Y156181*
Y153681*
Y151181*
Y148681*
Y146181*
Y143681*
Y141181*
Y138681*
Y136181*
Y133681*
Y131181*
Y128681*
X-952233Y85778*
Y83278*
Y80778*
Y78278*
Y75778*
Y73278*
Y70778*
G54D208*
G55*
X-281321Y835797D03*
X-281421Y842297*
X-308790Y705913*
X-306498Y407657*
X-295503Y403595*
X-284223Y407960*
X-300028Y278010*
X-300519Y163274*
X-385503Y760533*
X-347192Y742498*
X-320921Y784097*
X-351362Y726197*
X-353562Y730697*
X-383831Y593466*
X-372738Y589341*
X-361494Y593542*
X-373184Y407294*
X-317646Y403499*
X-328671Y407594*
X-339725Y403340*
X-350946Y407339*
X-362021Y403126*
X-384175Y403160*
X-450443Y823297*
X-439241Y831408*
X-437885Y839716*
X-439511Y822664*
X-396582Y780135*
X-396070Y748800*
X-412703Y653269*
X-412564Y658179*
X-413577Y663788*
X-411930Y668635*
X-411798Y673969*
X-411671Y678775*
X-410211Y687695*
Y683495*
X-412631Y643836*
X-412664Y648541*
X-412831Y631136*
X-412731Y639636*
X-412831Y635336*
X-394902Y589347*
X-416959Y581044*
X-405906Y585284*
X-450301Y568603*
X-439159Y572748*
X-428078Y576908*
X-448321Y475497*
X-425787Y439754*
Y435654*
X-417325Y407349*
X-395188Y407367*
X-406308Y403177*
X-450684Y403294*
X-439484Y407394*
X-428384Y403194*
X-481011Y827164*
X-459887Y706280*
X-468979Y519992*
X-486030Y522091*
X-461360Y561290*
X-478924Y496906*
X-471420Y463945*
X-471537Y451509*
X-594221Y132235*
X-579055Y132361*
X-694984Y410363*
X-702616*
X-723658Y396569*
X-723704Y388038*
X-723434Y379552*
X-723587Y435221*
X-765521Y532197*
X-881921Y530597*
X-906230Y463174*
X-889730Y446774*
X-885630Y442474*
X-902130Y459074*
X-924521Y380897*
X-969030Y446574*
X-973130Y442374*
X-956630Y459074*
X-952530Y463174*
X-983521Y378697*
X-985721Y369297*
Y373397*
X-985821Y347697*
X-985751Y355964*
X-985758Y364483*
X-985850Y351810*
X-962021Y71997*
G54D207*
G55*
X-266715Y432134D03*
X-319509Y740243*
X-399134Y753438*
X-391452Y748347*
X-450003Y497408*
X-453164Y506531*
X-486521Y464097*
X-477577Y446980*
X-478494Y456274*
X-540995Y449409*
X-536521Y462697*
X-541034Y454190*
G54D212*
G55*
X-307881Y731647D03*
X-305321*
X-302761*
Y738147*
X-307881*
G54D240*
G55*
X-429221Y794347D03*
Y778847*
X-510626Y862058*
Y877558*
G54D241*
G55*
X-430769Y97245D03*
Y87796*
Y78348*
G54D242*
G55*
X-746855Y521772D03*
Y516772*
Y511772*
X-766855*
Y516772*
Y521772*
X-746855Y506772*
X-766855*
G54D231*
G55*
X-388087Y824748D03*
X-425637*
G54D232*
G55*
X-311339Y364173D03*
Y361023*
Y357874*
Y354724*
Y351575*
Y348425*
Y345275*
Y342126*
Y338976*
Y335827*
Y332677*
Y329527*
Y326378*
Y323228*
Y320079*
Y316929*
Y313779*
Y310630*
Y246063*
Y242913*
Y239764*
Y236614*
Y233465*
Y230315*
Y227165*
Y224016*
Y220866*
Y217717*
Y214567*
Y211417*
Y208268*
Y205118*
Y201969*
Y198819*
Y195669*
Y192520*
X-321221Y362598*
Y359449*
Y356299*
Y353149*
Y350000*
Y346850*
Y343701*
Y340551*
Y337401*
Y334252*
Y331102*
Y327953*
Y324803*
Y321653*
Y318504*
Y315354*
Y312205*
Y309055*
Y244488*
Y241339*
Y238189*
Y235039*
Y231890*
Y228740*
Y225591*
Y222441*
Y219291*
Y216142*
Y212992*
Y209843*
Y206693*
Y203543*
Y200394*
Y197244*
Y194095*
Y190945*
X-411339Y106693*
Y103543*
Y100393*
Y97243*
Y94093*
Y90943*
Y87798*
X-401459Y108268*
Y105118*
Y101968*
Y98818*
Y95668*
Y92518*
Y89368*
X-411339Y84648*
X-401459Y86223*
Y83073*
X-411339Y81498*
Y78348*
Y75198*
Y72048*
Y68898*
X-401459Y79923*
Y76773*
Y73623*
Y70473*
G54D208*
G55*
X-284721Y835797D03*
X-284821Y842297*
X-312190Y705913*
X-309898Y407657*
X-298903Y403595*
X-287623Y407960*
X-303428Y278010*
X-303919Y163274*
X-350592Y742498*
X-324321Y784097*
X-354762Y726197*
X-356962Y730697*
X-376138Y589341*
X-364894Y593542*
X-376584Y407294*
X-321046Y403499*
X-332071Y407594*
X-343125Y403340*
X-354346Y407339*
X-365421Y403126*
X-453843Y823297*
X-442641Y831408*
X-441285Y839716*
X-442911Y822664*
X-388903Y760533*
X-399982Y780135*
X-399470Y748800*
X-416103Y653269*
X-415964Y658179*
X-416977Y663788*
X-415330Y668635*
X-415198Y673969*
X-415071Y678775*
X-413611Y687695*
Y683495*
X-416031Y643836*
X-416064Y648541*
X-416231Y631136*
X-416131Y639636*
X-416231Y635336*
X-398302Y589347*
X-387231Y593466*
X-420359Y581044*
X-409306Y585284*
X-453701Y568603*
X-442559Y572748*
X-431478Y576908*
X-451721Y475497*
X-429187Y439754*
Y435654*
X-420725Y407349*
X-387575Y403160*
X-398588Y407367*
X-409708Y403177*
X-454084Y403294*
X-442884Y407394*
X-431784Y403194*
X-484411Y827164*
X-463287Y706280*
X-472379Y519992*
X-489430Y522091*
X-464760Y561290*
X-482324Y496906*
X-474820Y463945*
X-474937Y451509*
X-582455Y132361*
X-597621Y132235*
X-698384Y410363*
X-706016*
X-727058Y396569*
X-727104Y388038*
X-726834Y379552*
X-726987Y435221*
X-768921Y532197*
X-885321Y530597*
X-909630Y463174*
X-893130Y446774*
X-889030Y442474*
X-905530Y459074*
X-927921Y380897*
X-972430Y446574*
X-976530Y442374*
X-960030Y459074*
X-955930Y463174*
X-986921Y378697*
X-989121Y369297*
Y373397*
X-989221Y347697*
X-989151Y355964*
X-989158Y364483*
X-989250Y351810*
X-965421Y71997*
G54D244*
G55*
X-749721Y529037D03*
Y531597*
Y534157*
X-757121*
Y531597*
Y529037*
G54D252*
G55*
X-402870Y792550D03*
G54D253*
G55*
X-462311Y843064D03*
G54D237*
G55*
X-304361Y259285D03*
X-340762Y717497*
X-486888Y855901*
X-513991Y130423*
X-768721Y527797*
G54D214*
G55*
X-299221Y821897D03*
X-303521*
X-287184Y542814*
X-282984Y527314*
X-287051Y527308*
X-287184Y535014*
X-282984Y534714*
X-297784Y550914*
X-296343Y170736*
X-344004Y838636*
X-327399Y713864*
X-316547Y266209*
X-316188Y281703*
X-316874Y166550*
X-316636Y148864*
X-444833Y843767*
X-455725Y743627*
X-413308Y749764*
X-421436Y507164*
X-421487Y432154*
X-455524Y177083*
X-465834Y860299*
X-460038Y743589*
X-471635Y707484*
X-476883Y538113*
X-477949Y565041*
X-473676Y553942*
X-474221Y507097*
X-464121Y507197*
X-478921Y485197*
X-468321Y507197*
X-459879Y177083*
X-470745Y150414*
X-683311Y421355*
X-740248Y512322*
X-740315Y519865*
X-740202Y504778*
X-761684Y379264*
X-902130Y459074*
X-885630Y442474*
X-906230Y463174*
X-889730Y446774*
X-947630Y471274*
X-886921Y392297*
X-925411Y153691*
X-951730Y467274*
X-968330Y450674*
X-964130Y454974*
G54D238*
G55*
X-376099Y789996D03*
Y774728*
G54D66*
G55*
X-309059Y536688D03*
X-305122*
X-309059Y532751*
X-305122*
X-301185*
X-309059Y528814*
X-305122*
X-301185*
X-305122Y438262*
Y430388*
X-309059*
X-301185Y434325*
X-305122*
X-309059*
X-301185Y438262*
X-309059*
X-403548Y536688*
X-399611*
X-407485Y532751*
X-403548*
X-399611*
X-407485Y528814*
X-403548*
X-399611*
X-407485Y438262*
X-403548*
X-399611*
X-407485Y434325*
X-403548*
X-399611*
X-403548Y430388*
X-399611*
G54D186*
G55*
X-908478Y401428D03*
G54D239*
G55*
X-365531Y738974D03*
Y721022*
G54D164*
G55*
X-400617Y774090D03*
Y760110*
X-406523*
Y774090*
G54D254*
G55*
X-482676Y818140D03*
G54D255*
G55*
X-298761Y259285D03*
X-335162Y717497*
X-481288Y855901*
X-508391Y130423*
X-763121Y527797*
G54D94*
G55*
X-301185Y509129D03*
X-305122*
X-309059*
X-312996*
X-301185Y513066*
X-305122*
X-309059*
X-312996*
X-301185Y517003*
X-305122*
X-309059*
X-312996*
X-301185Y520940*
X-305122*
X-309059*
X-312996*
X-301185Y524877*
X-305122*
X-309059*
X-312996*
Y528814*
Y532751*
Y536688*
X-301185Y442199*
X-305122*
X-309059*
X-312996*
X-301185Y446136*
X-305122*
X-309059*
X-312996*
X-301185Y450073*
X-305122*
X-309059*
X-312996*
X-301185Y454010*
X-305122*
X-309059*
X-312996*
X-301185Y457947*
X-305122*
X-309059*
X-312996*
X-301185Y461884*
X-305122*
X-309059*
X-312996*
X-301185Y465821*
X-305122*
X-309059*
X-312996*
X-301185Y469758*
X-305122*
X-309059*
X-312996*
X-301185Y473695*
X-305122*
X-309059*
X-312996*
X-301185Y477632*
X-305122*
X-309059*
X-312996*
X-301185Y481569*
X-305122*
X-309059*
X-312996*
X-301185Y485507*
X-305122*
X-309059*
X-312996*
X-301185Y489444*
X-305122*
X-309059*
X-312996*
X-301185Y493381*
X-305122*
X-309059*
X-312996*
X-301185Y497318*
X-305122*
X-309059*
X-312996*
X-301185Y501255*
X-305122*
X-309059*
X-312996*
X-301185Y505192*
X-305122*
X-309059*
X-312996*
Y430388*
Y434325*
Y438262*
X-316933Y509129*
X-320870*
X-324807*
X-328744*
X-332681*
X-336618*
X-340555*
X-344492*
X-348429*
X-352366*
X-356304*
X-360241*
X-364178*
X-368115*
X-372052*
X-375989*
X-379926*
X-383863*
X-316933Y513066*
X-320870*
X-324807*
X-328744*
X-332681*
X-336618*
X-340555*
X-344492*
X-348429*
X-352366*
X-356304*
X-360241*
X-364178*
X-368115*
X-372052*
X-375989*
X-379926*
X-383863*
X-316933Y517003*
X-320870*
X-324807*
X-328744*
X-332681*
X-336618*
X-340555*
X-344492*
X-348429*
X-352366*
X-356304*
X-360241*
X-364178*
X-368115*
X-372052*
X-375989*
X-379926*
X-383863*
X-316933Y520940*
X-320870*
X-324807*
X-328744*
X-332681*
X-336618*
X-340555*
X-344492*
X-348429*
X-352366*
X-356304*
X-360241*
X-364178*
X-368115*
X-372052*
X-375989*
X-379926*
X-383863*
X-316933Y524877*
X-320870*
X-324807*
X-328744*
X-332681*
X-336618*
X-340555*
X-344492*
X-348429*
X-352366*
X-356304*
X-360241*
X-364178*
X-368115*
X-372052*
X-375989*
X-379926*
X-383863*
X-316933Y528814*
X-320870*
X-324807*
X-328744*
X-332681*
X-336618*
X-340555*
X-344492*
X-348429*
X-352366*
X-356304*
X-360241*
X-364178*
X-368115*
X-372052*
X-375989*
X-379926*
X-383863*
X-316933Y532751*
X-320870*
X-324807*
X-328744*
X-332681*
X-336618*
X-340555*
X-344492*
X-348429*
X-352366*
X-356304*
X-360241*
X-364178*
X-368115*
X-372052*
X-375989*
X-379926*
X-383863*
X-316933Y536688*
X-320870*
X-324807*
X-328744*
X-332681*
X-336618*
X-340555*
X-344492*
X-348429*
X-352366*
X-356304*
X-360241*
X-364178*
X-368115*
X-372052*
X-375989*
X-379926*
X-383863*
X-316933Y442199*
X-320870*
X-324807*
X-328744*
X-332681*
X-336618*
X-340555*
X-344492*
X-348429*
X-352366*
X-356304*
X-360241*
X-364178*
X-368115*
X-372052*
X-375989*
X-379926*
X-383863*
X-316933Y446136*
X-320870*
X-324807*
X-328744*
X-332681*
X-336618*
X-340555*
X-344492*
X-348429*
X-352366*
X-356304*
X-360241*
X-364178*
X-368115*
X-372052*
X-375989*
X-379926*
X-383863*
X-316933Y450073*
X-320870*
X-324807*
X-328744*
X-332681*
X-336618*
X-340555*
X-344492*
X-348429*
X-352366*
X-356304*
X-360241*
X-364178*
X-368115*
X-372052*
X-375989*
X-379926*
X-383863*
X-316933Y454010*
X-320870*
X-324807*
X-328744*
X-332681*
X-336618*
X-340555*
X-344492*
X-348429*
X-352366*
X-356304*
X-360241*
X-364178*
X-368115*
X-372052*
X-375989*
X-379926*
X-383863*
X-316933Y457947*
X-320870*
X-324807*
X-328744*
X-332681*
X-336618*
X-340555*
X-344492*
X-348429*
X-352366*
X-356304*
X-360241*
X-364178*
X-368115*
X-372052*
X-375989*
X-379926*
X-383863*
X-316933Y461884*
X-320870*
X-324807*
X-328744*
X-332681*
X-336618*
X-340555*
X-344492*
X-348429*
X-352366*
X-356304*
X-360241*
X-364178*
X-368115*
X-372052*
X-375989*
X-379926*
X-383863*
X-316933Y465821*
X-320870*
X-324807*
X-328744*
X-332681*
X-336618*
X-340555*
X-344492*
X-348429*
X-352366*
X-356304*
X-360241*
X-364178*
X-368115*
X-372052*
X-375989*
X-379926*
X-383863*
X-316933Y469758*
X-320870*
X-324807*
X-328744*
X-332681*
X-336618*
X-340555*
X-344492*
X-348429*
X-352366*
X-356304*
X-360241*
X-364178*
X-368115*
X-372052*
X-375989*
X-379926*
X-383863*
X-316933Y473695*
X-320870*
X-324807*
X-328744*
X-332681*
X-336618*
X-340555*
X-344492*
X-348429*
X-352366*
X-356304*
X-360241*
X-364178*
X-368115*
X-372052*
X-375989*
X-379926*
X-383863*
X-316933Y477632*
X-320870*
X-324807*
X-328744*
X-332681*
X-336618*
X-340555*
X-344492*
X-348429*
X-352366*
X-356304*
X-360241*
X-364178*
X-368115*
X-372052*
X-375989*
X-379926*
X-383863*
X-316933Y481569*
X-320870*
X-324807*
X-328744*
X-332681*
X-336618*
X-340555*
X-344492*
X-348429*
X-352366*
X-356304*
X-360241*
X-364178*
X-368115*
X-372052*
X-375989*
X-379926*
X-383863*
X-316933Y485507*
X-320870*
X-324807*
X-328744*
X-332681*
X-336618*
X-340555*
X-344492*
X-348429*
X-352366*
X-356304*
X-360241*
X-364178*
X-368115*
X-372052*
X-375989*
X-379926*
X-383863*
X-316933Y489444*
X-320870*
X-324807*
X-328744*
X-332681*
X-336618*
X-340555*
X-344492*
X-348429*
X-352366*
X-356304*
X-360241*
X-364178*
X-368115*
X-372052*
X-375989*
X-379926*
X-383863*
X-316933Y493381*
X-320870*
X-324807*
X-328744*
X-332681*
X-336618*
X-340555*
X-344492*
X-348429*
X-352366*
X-356304*
X-360241*
X-364178*
X-368115*
X-372052*
X-375989*
X-379926*
X-383863*
X-316933Y497318*
X-320870*
X-324807*
X-328744*
X-332681*
X-336618*
X-340555*
X-344492*
X-348429*
X-352366*
X-356304*
X-360241*
X-364178*
X-368115*
X-372052*
X-375989*
X-379926*
X-383863*
X-316933Y501255*
X-320870*
X-324807*
X-328744*
X-332681*
X-336618*
X-340555*
X-344492*
X-348429*
X-352366*
X-356304*
X-360241*
X-364178*
X-368115*
X-372052*
X-375989*
X-379926*
X-383863*
X-316933Y505192*
X-320870*
X-324807*
X-328744*
X-332681*
X-336618*
X-340555*
X-344492*
X-348429*
X-352366*
X-356304*
X-360241*
X-364178*
X-368115*
X-372052*
X-375989*
X-379926*
X-383863*
X-316933Y430388*
X-320870*
X-324807*
X-328744*
X-332681*
X-336618*
X-340555*
X-344492*
X-348429*
X-352366*
X-356304*
X-360241*
X-364178*
X-368115*
X-372052*
X-375989*
X-379926*
X-383863*
X-316933Y434325*
X-320870*
X-324807*
X-328744*
X-332681*
X-336618*
X-340555*
X-344492*
X-348429*
X-352366*
X-356304*
X-360241*
X-364178*
X-368115*
X-372052*
X-375989*
X-379926*
X-383863*
X-316933Y438262*
X-320870*
X-324807*
X-328744*
X-332681*
X-336618*
X-340555*
X-344492*
X-348429*
X-352366*
X-356304*
X-360241*
X-364178*
X-368115*
X-372052*
X-375989*
X-379926*
X-383863*
X-399611Y509129*
X-403548*
X-407485*
X-399611Y513066*
X-403548*
X-407485*
X-399611Y517003*
X-403548*
X-407485*
X-399611Y520940*
X-403548*
X-407485*
X-399611Y524877*
X-403548*
X-407485*
X-387800Y509129*
X-391737*
X-395674*
X-387800Y513066*
X-391737*
X-395674*
X-387800Y517003*
X-391737*
X-395674*
X-387800Y520940*
X-391737*
X-395674*
X-387800Y524877*
X-391737*
X-395674*
X-387800Y528814*
X-391737*
X-395674*
X-387800Y532751*
X-391737*
X-395674*
X-387800Y536688*
X-391737*
X-395674*
X-399611Y442199*
X-403548*
X-407485*
X-399611Y446136*
X-403548*
X-407485*
X-399611Y450073*
X-403548*
X-407485*
X-399611Y454010*
X-403548*
X-407485*
X-399611Y457947*
X-403548*
X-407485*
X-399611Y461884*
X-403548*
X-407485*
X-399611Y465821*
X-403548*
X-407485*
X-399611Y469758*
X-403548*
X-407485*
X-399611Y473695*
X-403548*
X-407485*
X-399611Y477632*
X-403548*
X-407485*
X-399611Y481569*
X-403548*
X-407485*
X-399611Y485507*
X-403548*
X-407485*
X-399611Y489444*
X-403548*
X-407485*
X-399611Y493381*
X-403548*
X-407485*
X-399611Y497318*
X-403548*
X-407485*
X-399611Y501255*
X-403548*
X-407485*
X-399611Y505192*
X-403548*
X-407485*
X-387800Y442199*
X-391737*
X-395674*
X-387800Y446136*
X-391737*
X-395674*
X-387800Y450073*
X-391737*
X-395674*
X-387800Y454010*
X-391737*
X-395674*
X-387800Y457947*
X-391737*
X-395674*
X-387800Y461884*
X-391737*
X-395674*
X-387800Y465821*
X-391737*
X-395674*
X-387800Y469758*
X-391737*
X-395674*
X-387800Y473695*
X-391737*
X-395674*
X-387800Y477632*
X-391737*
X-395674*
X-387800Y481569*
X-391737*
X-395674*
X-387800Y485507*
X-391737*
X-395674*
X-387800Y489444*
X-391737*
X-395674*
X-387800Y493381*
X-391737*
X-395674*
X-387800Y497318*
X-391737*
X-395674*
X-387800Y501255*
X-391737*
X-395674*
X-387800Y505192*
X-391737*
X-395674*
X-387800Y430388*
X-391737*
X-395674*
X-387800Y434325*
X-391737*
X-395674*
X-387800Y438262*
X-391737*
X-395674*
G54D173*
G55*
X-289121Y279897D03*
Y290897*
Y176897*
Y165897*
X-441821Y789397*
Y778397*
X-530972Y476587*
Y487587*
X-539770Y476641*
Y487641*
G54D168*
G55*
X-396580Y771037D03*
Y769069*
Y767100*
Y765131*
Y763163*
X-410560*
Y765131*
Y767100*
Y769069*
Y771037*
G54D190*
G55*
X-898735Y406546D03*
Y403987*
Y401428*
Y398869*
Y396310*
X-918221*
Y398869*
Y401428*
Y403987*
Y406546*
G54D248*
G55*
X-340603Y712583D03*
X-335746Y712587*
X-448921Y795497*
X-404305Y753142*
X-448713Y522164*
X-453584Y523419*
X-422155Y454968*
X-439660Y465845*
X-430845Y503734*
X-426986Y454869*
X-500574Y440263*
X-458798Y402678*
X-577651Y462046*
X-607629Y531642*
X-602807*
X-597940*
G54D256*
G55*
X-482676Y815440D03*
G54D257*
G55*
X-403570Y767100D03*
G54D250*
G55*
X-456790Y720257D03*
X-459350*
X-461910*
X-464470*
Y736437*
X-461910*
X-459350*
X-456790*
X-473971Y497197*
X-471471*
X-468971*
X-466471*
X-463971*
X-461471*
X-458971*
X-456471*
Y476597*
X-458971*
X-461471*
X-463971*
X-466471*
X-468971*
X-471471*
X-473971*
X-464470Y169507*
X-461910*
X-459350*
X-456790*
Y153327*
X-459350*
X-461910*
X-464470*
G54D188*
G55*
X-903360Y391685D03*
X-905919*
X-908478*
X-911037*
X-913596*
Y411171*
X-911037*
X-908478*
X-905919*
X-903360*
G54D248*
G55*
X-340603Y706983D03*
X-335746Y706987*
X-448921Y789897*
X-404305Y747542*
X-448713Y516564*
X-453584Y517819*
X-422155Y449368*
X-439660Y460245*
X-430845Y498134*
X-426986Y449269*
X-458798Y397078*
X-500574Y434663*
X-577651Y456446*
X-607629Y526042*
X-602807*
X-597940*
G54D227*
G55*
X-939210Y409442D03*
X-928210*
X-939221Y400697*
X-928221*
G54D222*
G55*
X-470443Y525321D03*
Y529061*
Y532801*
X-479443*
Y525321*
G54D258*
G55*
X-402870Y789850D03*
G54D226*
G55*
X-504989Y509569D03*
Y494569*
G54D66*
X-771361Y-182763D02*
G01Y-262763D01*
Y-218263D02*
G01X373639D01*
X-771361Y-262763D02*
G01X373639D01*
X-775361Y-166763D02*
G75*
G03X-775361Y-166763I-12000D01*
X-780511D02*
G03X-780511Y-166763I-6850D01*
X-787361Y-182763D02*
G01Y-150763D01*
X-771361Y-166763D02*
G01X-803361D01*
X-771361Y-182763D02*
G01X373639D01*
X-413861D02*
G01Y-262763D01*
X-276361Y-182763D02*
G01Y-262763D01*
X-161361Y-182763D02*
G01Y-262763D01*
X6139Y-182763D02*
G01Y-262763D01*
X176139Y-182763D02*
G01Y-262763D01*
X373639Y-182763D02*
G01Y-262763D01*
X401639Y-166763D02*
G03X401639Y-166763I-12000D01*
X396489D02*
G03X396489Y-166763I-6850D01*
X389639Y-182763D02*
G01Y-150763D01*
X405639Y-166763D02*
G01X373639D01*
G54D10*
X-1003937Y-3937D02*
G03X-1000000Y-7874I3937D01*
X-1031496Y-31496D02*
G03X-1027559Y-35433I3937D01*
X-986221Y-7874D02*
G03X-986221Y0J3937D01*
Y-7874D02*
G01X-1000000D01*
X-1027559Y-35433D02*
G01X791338D01*
X-1031496Y95866D02*
G01Y-31496D01*
X-996063Y3937D02*
G03X-992126Y0I3937D01*
X-996063Y39370D02*
G03X-1003937Y39370I-3937D01*
X-996063Y3937D02*
G03X-992126Y0I3937D01*
Y0D02*
G01X-318898D01*
Y0D02*
G01X-992126D01*
X-955512D02*
G01X-986221D01*
X-996063Y3937D02*
G01Y103740D01*
Y39370D02*
G01Y70079D01*
X-1003937Y-3937D02*
G01Y39370D01*
X-1027559Y99803D02*
G03X-1031496Y95866J-3937D01*
X-1003937D02*
G03X-1007874Y99803I-3937D01*
X-996063Y103740D02*
G03X-1000000Y107677I-3937D01*
X-1003937Y70079D02*
G03X-996063Y70079I3937D01*
X-1029528Y107677D02*
G01X-1000000D01*
X-1007874Y99803D02*
G01X-1027559D01*
X-1003937Y70079D02*
G01Y95866D01*
X-1031496Y109646D02*
G01X-1029528Y107677D01*
X-1031496Y109646D02*
G01Y134055D01*
X-1002166Y136024D02*
G03X-1002166Y143504J3740D01*
X-1000000Y187599D02*
G03X-996063Y191536J3937D01*
X-1029528Y187599D02*
G01X-1000000D01*
X-1029528Y143504D02*
G01X-1002166D01*
X-1029528Y136024D02*
G01X-1002166D01*
X-1029528D02*
G01X-1031496Y134055D01*
X-1029528Y187599D02*
G01X-1031496Y185630D01*
Y145473D02*
G01X-1029528Y143504D01*
X-996063Y261221D02*
G01Y191536D01*
X-1031496Y145473D02*
G01Y185630D01*
X-996063Y261221D02*
G03X-1000000Y265158I-3937D01*
X-1029528D02*
G01X-1000000D01*
X-1031496Y267126D02*
G01X-1029528Y265158D01*
X-1031496Y267126D02*
G01Y543504D01*
X-1002166Y545473D02*
G03X-1002166Y552953J3740D01*
X-1029528D02*
G01X-1002166D01*
X-1029528Y545473D02*
G01X-1002166D01*
X-1031496Y554922D02*
G01X-1029528Y552953D01*
Y545473D02*
G01X-1031496Y543504D01*
Y554922D02*
G01Y595079D01*
X-1007874Y604922D02*
G03X-1003937Y608859J3937D01*
X-1031496D02*
G03X-1027559Y604922I3937D01*
X-1000000Y597048D02*
G03X-996063Y600985J3937D01*
X-1027559Y604922D02*
G01X-1007874D01*
X-1029528Y597048D02*
G01X-1000000D01*
X-1029528D02*
G01X-1031496Y595079D01*
X-996063Y921260D02*
G01Y600985D01*
X-1003937Y608859D02*
G01Y708662D01*
X-1031496Y956693D02*
G01Y608859D01*
X-1003937Y739370D02*
G03X-996063Y739370I3937D01*
Y708662D02*
G03X-1003937Y708662I-3937D01*
X-996063D02*
G01Y739370D01*
X-1003937D02*
G01Y929134D01*
X-992126Y925197D02*
G03X-996063Y921260J-3937D01*
X-1000000Y933071D02*
G03X-1003937Y929134J-3937D01*
X-986221Y925197D02*
G03X-986221Y933071J3937D01*
X-1027559Y960630D02*
G03X-1031496Y956693J-3937D01*
X-992126Y925197D02*
G03X-996063Y921260J-3937D01*
X791338Y960630D02*
G01X-1027559D01*
X-1000000Y933071D02*
G01X-986221D01*
X-992126Y925197D02*
G01X-240158D01*
X-986221D02*
G01X-955512D01*
X-992126D02*
G01X-240158D01*
X-955512Y0D02*
G03X-955512Y-7874J-3937D01*
X-769685D02*
G01X-955512D01*
Y933071D02*
G03X-955512Y925197J-3937D01*
Y933071D02*
G01X-750000D01*
X-769685Y-7874D02*
G03X-769685Y0J3937D01*
X-738977D02*
G01X-769685D01*
X-755164Y-252763D02*
G01Y-235263D01*
X-746868D02*
G01X-755164Y-246055D01*
X-745558Y-252763D02*
G01X-751453Y-241097D01*
X-737883Y-252763D02*
G01Y-235263D01*
X-727839Y-252763*
Y-235263*
X-715361Y-252763D02*
G01X-717108Y-252471D01*
X-718636Y-251305*
X-719946Y-249555*
X-720820Y-247513*
X-721256Y-245180*
Y-242846*
X-720820Y-240513*
X-719946Y-238471*
X-718636Y-236722*
X-717108Y-235555*
X-715361Y-235263*
X-713615Y-235555*
X-712086Y-236722*
X-710776Y-238471*
X-709902Y-240513*
X-709466Y-242846*
Y-245180*
X-709902Y-247513*
X-710776Y-249555*
X-712086Y-251305*
X-713615Y-252471*
X-715361Y-252763*
X-702446D02*
G01X-693276Y-235263D01*
X-702446D02*
G01X-693276Y-252763D01*
X-658494D02*
G01X-667228D01*
Y-235263*
X-658494*
X-661988Y-243721D02*
G01X-667228D01*
X-649946Y-252763D02*
G01X-640776Y-235263D01*
X-649946D02*
G01X-640776Y-252763D01*
X-632228D02*
G01Y-235263D01*
X-626988*
X-625241Y-236138*
X-623931Y-238180*
X-623494Y-240513*
X-623931Y-242846*
X-625023Y-244596*
X-626988Y-245472*
X-632228*
X-615820Y-252763D02*
G01X-610361Y-235263D01*
X-604902Y-252763*
X-606868Y-246638D02*
G01X-613855D01*
X-597883Y-252763D02*
G01Y-235263D01*
X-587839Y-252763*
Y-235263*
X-580164Y-252763D02*
G01Y-235263D01*
X-575798*
X-574051Y-236138*
X-572741Y-237305*
X-571649Y-239054*
X-570776Y-241097*
X-570558Y-244013*
X-570776Y-246930*
X-571649Y-248972*
X-572741Y-250722*
X-574051Y-251888*
X-575798Y-252763*
X-580164*
X-553494D02*
G01X-562228D01*
Y-235263*
X-553494*
X-556988Y-243721D02*
G01X-562228D01*
X-544728Y-252763D02*
G01Y-235263D01*
X-539269*
X-537523Y-236138*
X-536431Y-237305*
X-535994Y-239638*
X-536431Y-241972*
X-537741Y-243430*
X-539269Y-244305*
X-544728*
X-539269D02*
G01X-535994Y-252763D01*
X-503615Y-243430D02*
G01X-502741Y-242555D01*
X-502086Y-241097*
X-501649Y-239054*
X-502086Y-237305*
X-502959Y-236138*
X-504488Y-235263*
X-510383*
Y-252763*
X-503178*
X-501649Y-251597*
X-500776Y-249846*
X-500339Y-247805*
X-500776Y-245763*
X-502086Y-244013*
X-503615Y-243430*
X-510383*
X-487861Y-252763D02*
G01X-489608Y-252471D01*
X-491136Y-251305*
X-492446Y-249555*
X-493320Y-247513*
X-493756Y-245180*
Y-242846*
X-493320Y-240513*
X-492446Y-238471*
X-491136Y-236722*
X-489608Y-235555*
X-487861Y-235263*
X-486115Y-235555*
X-484586Y-236722*
X-483276Y-238471*
X-482402Y-240513*
X-481966Y-242846*
Y-245180*
X-482402Y-247513*
X-483276Y-249555*
X-484586Y-251305*
X-486115Y-252471*
X-487861Y-252763*
X-475820D02*
G01X-470361Y-235263D01*
X-464902Y-252763*
X-466868Y-246638D02*
G01X-473855D01*
X-457228Y-252763D02*
G01Y-235263D01*
X-451769*
X-450023Y-236138*
X-448931Y-237305*
X-448494Y-239638*
X-448931Y-241972*
X-450241Y-243430*
X-451769Y-244305*
X-457228*
X-451769D02*
G01X-448494Y-252763D01*
X-440164D02*
G01Y-235263D01*
X-435798*
X-434051Y-236138*
X-432741Y-237305*
X-431649Y-239054*
X-430776Y-241097*
X-430558Y-244013*
X-430776Y-246930*
X-431649Y-248972*
X-432741Y-250722*
X-434051Y-251888*
X-435798Y-252763*
X-440164*
X-738977Y0D02*
G03X-738977Y-7874J-3937D01*
X-522835D02*
G01X-738977D01*
X-719292Y933071D02*
G03X-719292Y925197J-3937D01*
X-750000D02*
G03X-750000Y933071J3937D01*
X-719292D02*
G01X-512992D01*
X-750000Y925197D02*
G01X-719292D01*
X-633538Y-207763D02*
G01Y-190263D01*
X-627861Y-204846*
X-622184Y-190263*
Y-207763*
X-610361D02*
G01X-611671Y-207471D01*
X-612981Y-206305*
X-613855Y-204263*
X-614291Y-201930*
X-613855Y-199596*
X-612981Y-197555*
X-611671Y-196388*
X-610361Y-196097*
X-609051Y-196388*
X-607741Y-197555*
X-606868Y-199596*
X-606649Y-201930*
X-606868Y-204263*
X-607741Y-206305*
X-609051Y-207471*
X-610361Y-207763*
X-588931Y-190263D02*
G01Y-207763D01*
Y-205139D02*
G01X-589804Y-206597D01*
X-591115Y-207471*
X-592643Y-207763*
X-594389Y-207180*
X-595699Y-205722*
X-596573Y-203972*
X-596791Y-201930*
X-596573Y-199888*
X-595699Y-198138*
X-594389Y-196680*
X-592643Y-196097*
X-591115Y-196388*
X-590023Y-196972*
X-588931Y-198138*
X-578636Y-199888D02*
G01X-571649D01*
X-572304Y-197846*
X-573396Y-196680*
X-574924Y-196097*
X-576453Y-196388*
X-577763Y-197263*
X-578636Y-199305*
X-579073Y-201055*
Y-202805*
X-578636Y-204555*
X-577544Y-206305*
X-576234Y-207471*
X-574706Y-207763*
X-573178Y-207180*
X-571649Y-205430*
X-557861Y-207763D02*
G01Y-190263D01*
X-522835Y-7874D02*
G03X-522835Y0J3937D01*
X-492126D02*
G03X-492126Y-7874J-3937D01*
X-365355D02*
G01X-492126D01*
Y0D02*
G01X-522835D01*
X-482284Y933071D02*
G03X-482284Y925197J-3937D01*
X-512992D02*
G03X-512992Y933071J3937D01*
Y925197D02*
G01X-482284D01*
Y933071D02*
G01X-316142D01*
X-380161Y-252763D02*
G01Y-235263D01*
X-382781Y-238763*
Y-252763D02*
G01X-377541D01*
X-366809Y-238180D02*
G01X-365499Y-236430D01*
X-363971Y-235555*
X-362224Y-235263*
X-360041Y-235846*
X-358513Y-237305*
X-358076Y-239054*
X-358294Y-240805*
X-359168Y-242263*
X-363534Y-245180*
X-365499Y-247221*
X-366809Y-250139*
X-367246Y-252763*
X-358076*
X-345161Y-235263D02*
G01X-346908Y-235846D01*
X-348218Y-237305*
X-349091Y-239054*
X-349746Y-241388*
X-349964Y-244013*
X-349746Y-246638*
X-349091Y-248972*
X-348218Y-250722*
X-346908Y-252180*
X-345161Y-252763*
X-343415Y-252180*
X-342104Y-250722*
X-341231Y-248972*
X-340576Y-246638*
X-340358Y-244013*
X-340576Y-241388*
X-341231Y-239054*
X-342104Y-237305*
X-343415Y-235846*
X-345161Y-235263*
X-327661D02*
G01X-329408Y-235846D01*
X-330718Y-237305*
X-331591Y-239054*
X-332246Y-241388*
X-332464Y-244013*
X-332246Y-246638*
X-331591Y-248972*
X-330718Y-250722*
X-329408Y-252180*
X-327661Y-252763*
X-325915Y-252180*
X-324604Y-250722*
X-323731Y-248972*
X-323076Y-246638*
X-322858Y-244013*
X-323076Y-241388*
X-323731Y-239054*
X-324604Y-237305*
X-325915Y-235846*
X-327661Y-235263*
X-307541Y-252763D02*
G01Y-235263D01*
X-315620Y-247805*
X-304702*
X-393278Y-207763D02*
G01Y-190263D01*
X-388038*
X-386291Y-191138*
X-384981Y-193180*
X-384544Y-195513*
X-384981Y-197846*
X-386073Y-199596*
X-388038Y-200472*
X-393278*
X-366608Y-191722D02*
G01X-367918Y-190846D01*
X-369446Y-190263*
X-371193*
X-373158Y-191138*
X-374686Y-192596*
X-375778Y-194347*
X-376651Y-197263*
X-376870Y-199888*
X-376433Y-202513*
X-375778Y-204263*
X-374468Y-206013*
X-372939Y-207180*
X-371411Y-207763*
X-369883*
X-368354Y-207180*
X-367044Y-206305*
X-365952Y-205139*
X-352165Y-198430D02*
G01X-351291Y-197555D01*
X-350636Y-196097*
X-350199Y-194054*
X-350636Y-192305*
X-351509Y-191138*
X-353038Y-190263*
X-358933*
Y-207763*
X-351728*
X-350199Y-206597*
X-349326Y-204846*
X-348889Y-202805*
X-349326Y-200763*
X-350636Y-199013*
X-352165Y-198430*
X-358933*
X-342961Y-213596D02*
G01X-329861D01*
X-323933Y-207763D02*
G01Y-190263D01*
X-313889Y-207763*
Y-190263*
X-301411Y-207763D02*
G01X-303158Y-207471D01*
X-304686Y-206305*
X-305996Y-204555*
X-306870Y-202513*
X-307306Y-200180*
Y-197846*
X-306870Y-195513*
X-305996Y-193471*
X-304686Y-191722*
X-303158Y-190555*
X-301411Y-190263*
X-299665Y-190555*
X-298136Y-191722*
X-296826Y-193471*
X-295952Y-195513*
X-295516Y-197846*
Y-200180*
X-295952Y-202513*
X-296826Y-204555*
X-298136Y-206305*
X-299665Y-207471*
X-301411Y-207763*
X-365355Y-7874D02*
G03X-365355Y0J3937D01*
X-334646D02*
G01X-365355D01*
X-311024Y-7874D02*
G03X-307087Y-3937J3937D01*
X-334646Y0D02*
G03X-334646Y-7874J-3937D01*
X-311024D02*
G01X-334646D01*
X-318898Y0D02*
G03X-314961Y3937J3937D01*
X-274410Y31595D02*
G03X-270473Y35532J3937D01*
X-303150Y31595D02*
G03X-307087Y27658J-3937D01*
X-318898Y0D02*
G03X-314961Y3937J3937D01*
X-307087Y27658D02*
G01Y-3937D01*
X-314961Y133859D02*
G01Y3937D01*
Y133859D02*
G01Y3937D01*
X-274410Y31595D02*
G01X-303150D01*
X-311024Y137796D02*
G03X-314961Y133859J-3937D01*
X-311024Y137796D02*
G03X-314961Y133859J-3937D01*
X-240158Y137796D02*
G01X-311024D01*
X-240158D02*
G01X-311024D01*
X-285433Y933071D02*
G03X-285433Y925197J-3937D01*
X-316142D02*
G03X-316142Y933071J3937D01*
X-285433D02*
G01X-224410D01*
X-316142Y925197D02*
G01X-285433D01*
X-218861Y-252763D02*
G01Y-235263D01*
X-221481Y-238763*
Y-252763D02*
G01X-216241D01*
X-250570Y-190263D02*
G01X-245111Y-207763D01*
X-239652Y-190263*
X-223244Y-207763D02*
G01X-231978D01*
Y-190263*
X-223244*
X-226738Y-198721D02*
G01X-231978D01*
X-214478Y-207763D02*
G01Y-190263D01*
X-209019*
X-207273Y-191138*
X-206181Y-192305*
X-205744Y-194638*
X-206181Y-196972*
X-207491Y-198430*
X-209019Y-199305*
X-214478*
X-209019D02*
G01X-205744Y-207763D01*
X-192611Y-208346D02*
G01X-193048Y-208055D01*
Y-207471*
X-192611Y-207180*
X-192174Y-207471*
Y-208055*
X-192611Y-208346*
X-270473Y125985D02*
G01Y35532D01*
X-266536Y129922D02*
G03X-270473Y125985J-3937D01*
X-260630Y129922D02*
G03X-260630Y137796J3937D01*
X-244882D02*
G03X-244882Y129922J-3937D01*
X-240158D02*
G03X-228347Y141733J11811D01*
X-260630Y129922D02*
G01X-266536D01*
X-240158D02*
G01X-244882D01*
X-240158Y137796D02*
G03X-236221Y141733J3937D01*
X-240158Y137796D02*
G03X-236221Y141733J3937D01*
X-228347Y368701D02*
G01Y141733D01*
X-236221Y413386D02*
G01Y141733D01*
X-244882Y137796D02*
G01X-260630D01*
X-204725Y409449D02*
G03X-208662Y405512J-3937D01*
X-232284Y417323D02*
G03X-236221Y413386J-3937D01*
X-232284Y417323D02*
G03X-236221Y413386J-3937D01*
X-212599Y372638D02*
G03X-208662Y376575J3937D01*
X-224410Y372638D02*
G03X-228347Y368701J-3937D01*
X-181103Y409449D02*
G01X-204725D01*
X-212599Y372638D02*
G01X-224410D01*
X-208662Y405512D02*
G01Y376575D01*
X-232284Y417323D02*
G01X-181103D01*
X-232284D02*
G01X-181103D01*
X-236221Y716536D02*
G03X-232284Y712599I3937D01*
X-224410Y724410D02*
G03X-220473Y720473I3937D01*
X-236221Y716536D02*
G03X-232284Y712599I3937D01*
X-220473Y720473D02*
G01X-96418D01*
Y712599D02*
G01X-232284D01*
X-96418D02*
G01X-232284D01*
X-224410Y933071D02*
G01Y724410D01*
X-236221Y921260D02*
G01Y716536D01*
Y921260D02*
G03X-240158Y925197I-3937D01*
X-236221Y921260D02*
G03X-240158Y925197I-3937D01*
X-143740Y216536D02*
G03X-139803Y212599I3937D01*
X-143740Y262205D02*
G03X-151614Y262205I-3937D01*
X-143740Y216536D02*
G03X-139803Y212599I3937D01*
X-151614Y216536D02*
G03X-139803Y204725I11811D01*
X-143740Y262205D02*
G01Y292914D01*
Y338583D02*
G01Y216536D01*
Y338583D02*
G01Y216536D01*
X-151614D02*
G01Y262205D01*
X-139803Y212599D02*
G01X-3937D01*
X-139803D02*
G01X-3937D01*
X-15748Y204725D02*
G01X-139803D01*
Y342520D02*
G03X-143740Y338583J-3937D01*
X-139803Y342520D02*
G03X-143740Y338583J-3937D01*
X-139803Y350394D02*
G03X-151614Y338583J-11811D01*
Y292914D02*
G03X-143740Y292914I3937D01*
X-151614D02*
G01Y338583D01*
X-62992Y342520D02*
G01X-139803D01*
X-62992D02*
G01X-139803D01*
X-181103Y409449D02*
G03X-169292Y421260J11811D01*
X-139803Y350394D02*
G01X-70866D01*
X-177166Y467717D02*
G03X-169292Y467717I3937D01*
X-181103Y417323D02*
G03X-177166Y421260J3937D01*
X-169292Y437008D02*
G03X-177166Y437008I-3937D01*
X-181103Y417323D02*
G03X-177166Y421260J3937D01*
X-169292Y437008D02*
G01Y421260D01*
Y570866D02*
G01Y467717D01*
X-177166Y421260D02*
G01Y578740D01*
Y421260D02*
G01Y578740D01*
Y467717D02*
G01Y437008D01*
X-173229Y582677D02*
G03X-177166Y578740J-3937D01*
X-165355Y574803D02*
G03X-169292Y570866J-3937D01*
X-173229Y582677D02*
G03X-177166Y578740J-3937D01*
X-173229Y582677D02*
G01X-96418D01*
X-173229D02*
G01X-96418D01*
Y574803D02*
G01X-165355D01*
X-103911Y-235263D02*
G01Y-252763D01*
X-108933Y-235263D02*
G01X-98889D01*
X-90996Y-250430D02*
G01X-89249Y-251888D01*
X-87284Y-252763*
X-85538*
X-83791Y-251888*
X-82481Y-250430*
X-81826Y-248388*
X-82263Y-246347*
X-83354Y-244596*
X-85319Y-243430*
X-87939Y-242846*
X-89468Y-241680*
X-90123Y-239638*
X-89686Y-237596*
X-88594Y-236138*
X-87066Y-235263*
X-85538*
X-84009Y-235846*
X-82699Y-237305*
X-74588Y-252763D02*
G01Y-235263D01*
X-68911Y-249846*
X-63234Y-235263*
Y-252763*
X-56214D02*
G01Y-235263D01*
X-51848*
X-50101Y-236138*
X-48791Y-237305*
X-47699Y-239054*
X-46826Y-241097*
X-46608Y-244013*
X-46826Y-246930*
X-47699Y-248972*
X-48791Y-250722*
X-50101Y-251888*
X-51848Y-252763*
X-56214*
X-125778Y-190263D02*
G01Y-207763D01*
X-117044*
X-99981D02*
G01Y-196097D01*
Y-198138D02*
G01X-100854Y-196972D01*
X-102165Y-196388*
X-103693Y-196097*
X-105221Y-196680*
X-106531Y-197846*
X-107405Y-199596*
X-107841Y-201930*
X-107405Y-204263*
X-106531Y-206013*
X-105221Y-207180*
X-103693Y-207763*
X-102165Y-207471*
X-100854Y-206597*
X-99981Y-205430*
X-90996Y-213013D02*
G01X-89686Y-213596D01*
X-87939Y-213013*
X-86848Y-211847*
X-85974Y-210388*
X-84665Y-205722*
X-81826Y-196097*
X-88813D02*
G01X-84665Y-205722D01*
X-72186Y-199888D02*
G01X-65199D01*
X-65854Y-197846*
X-66946Y-196680*
X-68474Y-196097*
X-70003Y-196388*
X-71313Y-197263*
X-72186Y-199305*
X-72623Y-201055*
Y-202805*
X-72186Y-204555*
X-71094Y-206305*
X-69784Y-207471*
X-68256Y-207763*
X-66728Y-207180*
X-65199Y-205430*
X-54468Y-207763D02*
G01Y-196097D01*
Y-198430D02*
G01X-53376Y-197263D01*
X-52284Y-196388*
X-50756Y-196097*
X-49665Y-196388*
X-48354Y-197263*
X-37186Y-205722D02*
G01X-36094Y-206888D01*
X-34566Y-207763*
X-33256*
X-31946Y-207180*
X-31073Y-206305*
X-30636Y-205139*
X-30854Y-203388*
X-31728Y-202513*
X-35658Y-200763*
X-36531Y-198721*
X-36094Y-197263*
X-35221Y-196388*
X-33911Y-196097*
X-32601Y-196388*
X-31291Y-197263*
X-62992Y342520D02*
G03X-59055Y346457J3937D01*
X-62992Y342520D02*
G03X-59055Y346457J3937D01*
X-70866Y350394D02*
G03X-66929Y354331J3937D01*
Y354331D02*
G01Y457481D01*
Y488189D02*
G03X-59055Y488189I3937D01*
Y457481D02*
G03X-66929Y457481I-3937D01*
X-55118Y515748D02*
G03X-66929Y503937J-11811D01*
Y488189D02*
G01Y503937D01*
X-96418Y582677D02*
G03X-92481Y586615J3937D01*
X-96418Y582677D02*
G03X-92481Y586615J3937D01*
X-96418Y574803D02*
G03X-84607Y586615J11811D01*
Y632284D02*
G01Y586615D01*
X-92481D02*
G01Y708662D01*
Y586615D02*
G01Y708662D01*
Y662992D02*
G03X-84607Y662992I3937D01*
Y632284D02*
G03X-92481Y632284I-3937D01*
X-84607Y708662D02*
G01Y662992D01*
X-92481D02*
G01Y632284D01*
Y708662D02*
G03X-96418Y712599I-3937D01*
X-92481Y708662D02*
G03X-96418Y712599I-3937D01*
X-84607Y708662D02*
G03X-96418Y720473I-11811D01*
X-11811Y-3937D02*
G03X-7874Y-7874I3937D01*
X31496D02*
G01X-7874D01*
X0Y3937D02*
G03X3937Y0I3937D01*
X0Y3937D02*
G03X3937Y0I3937D01*
X0Y3937D02*
G01Y208662D01*
X-11811Y-3937D02*
G01Y200788D01*
X755905Y0D02*
G01X3937D01*
X755905D02*
G01X3937D01*
X-11811Y200788D02*
G03X-15748Y204725I-3937D01*
X0Y208662D02*
G03X-3937Y212599I-3937D01*
X0Y208662D02*
G03X-3937Y212599I-3937D01*
X-59055Y503937D02*
G01Y346457D01*
Y503937D02*
G01Y346457D01*
Y488189D02*
G01Y457481D01*
X-23622Y552559D02*
G03X-27559Y548622J-3937D01*
X-11811Y552559D02*
G03X-7874Y556496J3937D01*
X-3937Y507874D02*
G03X0Y511811J3937D01*
X-3937Y507874D02*
G03X0Y511811J3937D01*
X-55118Y507874D02*
G03X-59055Y503937J-3937D01*
X-31496Y515748D02*
G03X-27559Y519685J3937D01*
X-55118Y507874D02*
G03X-59055Y503937J-3937D01*
X-23622Y552559D02*
G01X-11811D01*
X0Y511811D02*
G01Y783465D01*
X-27559Y519685D02*
G01Y548622D01*
X-55118Y515748D02*
G01X-31496D01*
X-3937Y507874D02*
G01X-55118D01*
X-3937D02*
G01X-55118D01*
X-7874Y556496D02*
G01Y783465D01*
X3937Y787402D02*
G03X0Y783465J-3937D01*
X3937Y787402D02*
G03X0Y783465J-3937D01*
X3937Y795276D02*
G03X-7874Y783465J-11811D01*
X3937Y795276D02*
G01X8661D01*
X3937Y787402D02*
G01X74803D01*
X3937D02*
G01X74803D01*
X51772Y-235263D02*
G01Y-252763D01*
X60506*
X68836Y-235263D02*
G01Y-247805D01*
X69709Y-250430*
X71456Y-252180*
X73639Y-252763*
X75822Y-252180*
X77569Y-250430*
X78442Y-247805*
Y-235263*
X95942Y-236722D02*
G01X94632Y-235846D01*
X93104Y-235263*
X91357*
X89392Y-236138*
X87864Y-237596*
X86772Y-239347*
X85899Y-242263*
X85680Y-244888*
X86117Y-247513*
X86772Y-249263*
X88082Y-251013*
X89611Y-252180*
X91139Y-252763*
X92667*
X94196Y-252180*
X95506Y-251305*
X96598Y-250139*
X103836Y-252763D02*
G01Y-235263D01*
X112132D02*
G01X103836Y-246055D01*
X113442Y-252763D02*
G01X107547Y-241097D01*
X126139Y-252763D02*
G01Y-244888D01*
X121772Y-235263*
X130506D02*
G01X126139Y-244888D01*
X25086Y-207763D02*
G01Y-190263D01*
X29452*
X31199Y-191138*
X32509Y-192305*
X33601Y-194054*
X34474Y-196097*
X34692Y-199013*
X34474Y-201930*
X33601Y-203972*
X32509Y-205722*
X31199Y-206888*
X29452Y-207763*
X25086*
X44114Y-199888D02*
G01X51101D01*
X50446Y-197846*
X49354Y-196680*
X47826Y-196097*
X46297Y-196388*
X44987Y-197263*
X44114Y-199305*
X43677Y-201055*
Y-202805*
X44114Y-204555*
X45206Y-206305*
X46516Y-207471*
X48044Y-207763*
X49572Y-207180*
X51101Y-205430*
X61614Y-205722D02*
G01X62706Y-206888D01*
X64234Y-207763*
X65544*
X66854Y-207180*
X67727Y-206305*
X68164Y-205139*
X67946Y-203388*
X67072Y-202513*
X63142Y-200763*
X62269Y-198721*
X62706Y-197263*
X63579Y-196388*
X64889Y-196097*
X66199Y-196388*
X67509Y-197263*
X82389Y-196097D02*
G01Y-207763D01*
Y-191430D02*
G01X81952Y-191138D01*
Y-190555*
X82389Y-190263*
X82826Y-190555*
Y-191138*
X82389Y-191430*
X96832Y-212138D02*
G01X98361Y-213305D01*
X100107Y-213596*
X101635Y-213305*
X102946Y-211847*
X103819Y-209805*
Y-196097*
Y-198430D02*
G01X102946Y-197263D01*
X101635Y-196388*
X100107Y-196097*
X98361Y-196680*
X97269Y-197846*
X96395Y-199888*
X95959Y-201930*
X96177Y-203680*
X97051Y-205722*
X98361Y-207180*
X100107Y-207763*
X101417Y-207471*
X102946Y-206305*
X103819Y-205139*
X113677Y-207763D02*
G01Y-196097D01*
Y-199013D02*
G01X114551Y-197555D01*
X115861Y-196388*
X117607Y-196097*
X119135Y-196388*
X120446Y-197555*
X121101Y-199596*
Y-207763*
X131614Y-199888D02*
G01X138601D01*
X137946Y-197846*
X136854Y-196680*
X135326Y-196097*
X133797Y-196388*
X132487Y-197263*
X131614Y-199305*
X131177Y-201055*
Y-202805*
X131614Y-204555*
X132706Y-206305*
X134016Y-207471*
X135544Y-207763*
X137072Y-207180*
X138601Y-205430*
X149332Y-207763D02*
G01Y-196097D01*
Y-198430D02*
G01X150424Y-197263D01*
X151516Y-196388*
X153044Y-196097*
X154135Y-196388*
X155446Y-197263*
X62204Y0D02*
G03X62204Y-7874J-3937D01*
X31496D02*
G03X31496Y0J3937D01*
X267716Y-7874D02*
G01X62204D01*
Y0D02*
G01X31496D01*
X74803Y787402D02*
G03X78740Y791339J3937D01*
X30315Y795276D02*
G03X34252Y799213J3937D01*
X24409Y795276D02*
G03X24409Y787402J-3937D01*
X8661D02*
G03X8661Y795276J3937D01*
X74803Y787402D02*
G03X78740Y791339J3937D01*
X24409Y795276D02*
G01X30315D01*
X24409Y787402D02*
G01X8661D01*
X34252Y799213D02*
G01Y889666D01*
X38189Y893603D02*
G03X34252Y889666J-3937D01*
X66929Y893603D02*
G03X70866Y897540J3937D01*
X38189Y893603D02*
G01X66929D01*
X70866Y897540D02*
G01Y929134D01*
X74803Y933071D02*
G03X70866Y929134J-3937D01*
X74803Y933071D02*
G01X88582D01*
X78740Y791339D02*
G01Y921260D01*
Y791339D02*
G01Y921260D01*
X119291Y933071D02*
G03X119291Y925197J-3937D01*
X82677D02*
G03X78740Y921260J-3937D01*
X88582Y925197D02*
G03X88582Y933071J3937D01*
X82677Y925197D02*
G03X78740Y921260J-3937D01*
X119291Y933071D02*
G01X305118D01*
X82677Y925197D02*
G01X755905D01*
X82677D02*
G01X755905D01*
X119291D02*
G01X88582D01*
X196089Y-252763D02*
G01Y-235263D01*
X193469Y-238763*
Y-252763D02*
G01X198709D01*
X213589Y-235263D02*
G01X211842Y-235846D01*
X210532Y-237305*
X209659Y-239054*
X209004Y-241388*
X208786Y-244013*
X209004Y-246638*
X209659Y-248972*
X210532Y-250722*
X211842Y-252180*
X213589Y-252763*
X215335Y-252180*
X216646Y-250722*
X217519Y-248972*
X218174Y-246638*
X218392Y-244013*
X218174Y-241388*
X217519Y-239054*
X216646Y-237305*
X215335Y-235846*
X213589Y-235263*
X227159Y-253346D02*
G01X235019Y-235263D01*
X248589Y-252763D02*
G01Y-235263D01*
X245969Y-238763*
Y-252763D02*
G01X251209D01*
X261941Y-245472D02*
G01X263469Y-243430D01*
X264779Y-242263*
X266526Y-241680*
X268054Y-242263*
X269146Y-243430*
X270019Y-245180*
X270237Y-247221*
X270019Y-248972*
X269146Y-250722*
X267835Y-252180*
X266307Y-252763*
X264561Y-252180*
X263032Y-250430*
X262159Y-247805*
X261941Y-244888*
X262377Y-241097*
X263032Y-239054*
X264124Y-237013*
X265652Y-235555*
X267181Y-235263*
X268709Y-235846*
X269801Y-237305*
X279659Y-253346D02*
G01X287519Y-235263D01*
X296941Y-238180D02*
G01X298251Y-236430D01*
X299779Y-235555*
X301526Y-235263*
X303709Y-235846*
X305237Y-237305*
X305674Y-239054*
X305456Y-240805*
X304582Y-242263*
X300216Y-245180*
X298251Y-247221*
X296941Y-250139*
X296504Y-252763*
X305674*
X318589Y-235263D02*
G01X316842Y-235846D01*
X315532Y-237305*
X314659Y-239054*
X314004Y-241388*
X313786Y-244013*
X314004Y-246638*
X314659Y-248972*
X315532Y-250722*
X316842Y-252180*
X318589Y-252763*
X320335Y-252180*
X321646Y-250722*
X322519Y-248972*
X323174Y-246638*
X323392Y-244013*
X323174Y-241388*
X322519Y-239054*
X321646Y-237305*
X320335Y-235846*
X318589Y-235263*
X336089Y-252763D02*
G01Y-235263D01*
X333469Y-238763*
Y-252763D02*
G01X338709D01*
X349441Y-238180D02*
G01X350751Y-236430D01*
X352279Y-235555*
X354026Y-235263*
X356209Y-235846*
X357737Y-237305*
X358174Y-239054*
X357956Y-240805*
X357082Y-242263*
X352716Y-245180*
X350751Y-247221*
X349441Y-250139*
X349004Y-252763*
X358174*
X243786Y-207763D02*
G01Y-190263D01*
X248152*
X249899Y-191138*
X251209Y-192305*
X252301Y-194054*
X253174Y-196097*
X253392Y-199013*
X253174Y-201930*
X252301Y-203972*
X251209Y-205722*
X249899Y-206888*
X248152Y-207763*
X243786*
X270019D02*
G01Y-196097D01*
Y-198138D02*
G01X269146Y-196972D01*
X267835Y-196388*
X266307Y-196097*
X264779Y-196680*
X263469Y-197846*
X262595Y-199596*
X262159Y-201930*
X262595Y-204263*
X263469Y-206013*
X264779Y-207180*
X266307Y-207763*
X267835Y-207471*
X269146Y-206597*
X270019Y-205430*
X283589Y-190263D02*
G01Y-207763D01*
X280532Y-196097D02*
G01X286646D01*
X297814Y-199888D02*
G01X304801D01*
X304146Y-197846*
X303054Y-196680*
X301526Y-196097*
X299997Y-196388*
X298687Y-197263*
X297814Y-199305*
X297377Y-201055*
Y-202805*
X297814Y-204555*
X298906Y-206305*
X300216Y-207471*
X301744Y-207763*
X303272Y-207180*
X304801Y-205430*
X267716Y-7874D02*
G03X267716Y0J3937D01*
X298425D02*
G01X267716D01*
X298425D02*
G03X298425Y-7874J-3937D01*
X483071D02*
G01X298425D01*
X335827Y933071D02*
G03X335827Y925197J-3937D01*
X305118D02*
G03X305118Y933071J3937D01*
X335827D02*
G01X522441D01*
X335827Y925197D02*
G01X305118D01*
X483071Y-7874D02*
G03X483071Y0J3937D01*
X513779D02*
G01X483071D01*
X513779D02*
G03X513779Y-7874J-3937D01*
X719291D02*
G01X513779D01*
X553149Y933071D02*
G03X553149Y925197J-3937D01*
X522441D02*
G03X522441Y933071J3937D01*
X553149D02*
G01X719291D01*
X553149Y925197D02*
G01X522441D01*
X763779Y-7874D02*
G03X767716Y-3937J3937D01*
X719291Y-7874D02*
G03X719291Y0J3937D01*
X750000D02*
G03X750000Y-7874J-3937D01*
X763779D02*
G01X750000D01*
X755905Y0D02*
G03X759842Y3937J3937D01*
X755905Y0D02*
G03X759842Y3937J3937D01*
X767716Y185827D02*
G01Y-3937D01*
X759842Y3937D02*
G01Y324213D01*
X750000Y0D02*
G01X719291D01*
X767716Y185827D02*
G03X759842Y185827I-3937D01*
Y216536D02*
G01Y185827D01*
Y216536D02*
G03X767716Y216536I3937D01*
Y316339D02*
G01Y216536D01*
X771653Y320276D02*
G03X767716Y316339J-3937D01*
X763779Y328150D02*
G03X759842Y324213J-3937D01*
X793307Y328150D02*
G01X763779D01*
X791338Y320276D02*
G01X771653D01*
X765945Y379725D02*
G03X765945Y372243J-3741D01*
X793307Y379725D02*
G01X765945D01*
X793307Y372244D02*
G01X765945D01*
X759842Y663977D02*
G03X763779Y660040I3937D01*
X759842Y663977D02*
G01Y733662D01*
X793307Y660040D02*
G01X763779D01*
Y737599D02*
G03X759842Y733662J-3937D01*
X793307Y737599D02*
G01X763779D01*
X765945Y789174D02*
G03X765945Y781694J-3740D01*
X767716Y829331D02*
G03X771653Y825394I3937D01*
X759842Y821457D02*
G03X763779Y817520I3937D01*
X767716Y855118D02*
G01Y829331D01*
X759842Y921260D02*
G01Y821457D01*
X771653Y825394D02*
G01X791338D01*
X793307Y817520D02*
G01X763779D01*
X793307Y789174D02*
G01X765945D01*
X793307Y781693D02*
G01X765945D01*
X767716Y855118D02*
G03X759842Y855118I-3937D01*
Y885827D02*
G03X767716Y885827I3937D01*
Y929134D02*
G01Y885827D01*
X759842D02*
G01Y855118D01*
Y921260D02*
G03X755905Y925197I-3937D01*
X767716Y929134D02*
G03X763779Y933071I-3937D01*
X750000D02*
G03X750000Y925197J-3937D01*
X719291D02*
G03X719291Y933071J3937D01*
X759842Y921260D02*
G03X755905Y925197I-3937D01*
X750000Y933071D02*
G01X763779D01*
X750000Y925197D02*
G01X719291D01*
X791338Y-35433D02*
G03X795275Y-31496J3937D01*
Y-31496D02*
G01Y316339D01*
Y316339D02*
G03X791338Y320276I-3937D01*
X795275Y370276D02*
G01Y330118D01*
Y330118D02*
G01X793307Y328150D01*
X795275Y658071D02*
G01Y381693D01*
Y381693D02*
G01X793307Y379725D01*
X795275Y370276D02*
G01X793307Y372244D01*
X795275Y658071D02*
G01X793307Y660040D01*
X795275Y779725D02*
G01Y739567D01*
Y739567D02*
G01X793307Y737599D01*
X791338Y825394D02*
G03X795275Y829331J3937D01*
Y829331D02*
G01Y956693D01*
Y815552D02*
G01Y791142D01*
Y815552D02*
G01X793307Y817520D01*
X795275Y779725D02*
G01X793307Y781693D01*
X795275Y791142D02*
G01X793307Y789174D01*
X795275Y956693D02*
G03X791338Y960630I-3937D01*
X-92481Y708661D02*
G03X-96418Y712598I-3937D01*
X-92481Y708661D02*
G03X-96418Y712598I-3937D01*
X-92481Y586614D02*
G01Y708661D01*
Y586614D02*
G01Y708661D01*
X-96418Y712598D02*
G01X-232284D01*
X-96418D02*
G01X-232284D01*
X-96418Y582677D02*
G03X-92481Y586614J3937D01*
X-96418Y582677D02*
G03X-92481Y586614J3937D01*
X-173229Y582677D02*
G01X-96418D01*
X-173229D02*
G01X-96418D01*
X-173229D02*
G03X-177166Y578740J-3937D01*
X-173229Y582677D02*
G03X-177166Y578740J-3937D01*
X-236221Y921260D02*
G03X-240158Y925197I-3937D01*
X-236221Y921260D02*
G03X-240158Y925197I-3937D01*
X-236221Y921260D02*
G01Y716535D01*
X-992126Y925197D02*
G01X-240158D01*
X-992126D02*
G01X-240158D01*
X-236221Y716535D02*
G03X-232284Y712598I3937D01*
X-236221Y716535D02*
G03X-232284Y712598I3937D01*
X-177166Y421260D02*
G01Y578740D01*
Y421260D02*
G01Y578740D01*
X-232284Y417323D02*
G03X-236221Y413386J-3937D01*
X-232284Y417323D02*
G03X-236221Y413386J-3937D01*
X-181103Y417323D02*
G03X-177166Y421260J3937D01*
X-181103Y417323D02*
G03X-177166Y421260J3937D01*
X-236221Y413386D02*
G01Y141732D01*
X-232284Y417323D02*
G01X-181103D01*
X-232284D02*
G01X-181103D01*
X-240158Y137795D02*
G03X-236221Y141732J3937D01*
X-240158Y137795D02*
G03X-236221Y141732J3937D01*
X-240158Y137795D02*
G01X-311024D01*
X-240158D02*
G01X-311024D01*
Y137795D02*
G03X-314961Y133858J-3937D01*
X-311024Y137795D02*
G03X-314961Y133858J-3937D01*
Y133858D02*
G01Y3937D01*
Y133858D02*
G01Y3937D01*
X-318898Y0D02*
G03X-314961Y3937J3937D01*
X-318898Y0D02*
G03X-314961Y3937J3937D01*
X-318898Y0D02*
G01X-992126D01*
X-318898D02*
G01X-992126D01*
Y925197D02*
G03X-996063Y921260J-3937D01*
X-992126Y925197D02*
G03X-996063Y921260J-3937D01*
Y921260D02*
G01Y600984D01*
X-1000000Y597047D02*
G03X-996063Y600984J3937D01*
X-1029528Y597047D02*
G01X-1000000D01*
X-1002166Y545472D02*
G03X-1002166Y552954J3741D01*
X-1029528Y545472D02*
G01X-1002166D01*
X-1029528Y552953D02*
G01X-1002166D01*
X-996063Y261220D02*
G03X-1000000Y265157I-3937D01*
X-996063Y261220D02*
G01Y191535D01*
X-1029528Y265157D02*
G01X-1000000D01*
Y187598D02*
G03X-996063Y191535J3937D01*
X-1029528Y187598D02*
G01X-1000000D01*
X-1002166Y136023D02*
G03X-1002166Y143503J3740D01*
X-996063Y103740D02*
G03X-1000000Y107677I-3937D01*
X-996063Y3937D02*
G01Y103740D01*
X-1029528Y107677D02*
G01X-1000000D01*
X-1029528Y136023D02*
G01X-1002166D01*
X-1029528Y143504D02*
G01X-1002166D01*
X-996063Y3937D02*
G03X-992126Y0I3937D01*
X-996063Y3937D02*
G03X-992126Y0I3937D01*
X-1031496Y554921D02*
G01Y595079D01*
Y595079D02*
G01X-1029528Y597047D01*
X-1031496Y267126D02*
G01Y543504D01*
Y543504D02*
G01X-1029528Y545472D01*
X-1031496Y554921D02*
G01X-1029528Y552953D01*
X-1031496Y267126D02*
G01X-1029528Y265157D01*
X-1031496Y145472D02*
G01Y185630D01*
Y185630D02*
G01X-1029528Y187598D01*
X-1031496Y109645D02*
G01Y134055D01*
Y109645D02*
G01X-1029528Y107677D01*
X-1031496Y145472D02*
G01X-1029528Y143504D01*
X-1031496Y134055D02*
G01X-1029528Y136023D01*
M02*
